FILE_TYPE = MACRO_DRAWING;
SET COLOR_WIRE YELLOW;
SET COLOR_PROP ORANGE;
SET COLOR_DOT WHITE;
SET COLOR_ARC YELLOW;
SET COLOR_BODY GREEN;
SET COLOR_NOTE PURPLE;
SET PROP_DISPLAY VALUE;
SET PAGE_NUMBER P95;
FORCEADD OFFPAGE..2
R 2
(-1975 -625);
FORCEPROP 2 LAST $XR0 95 
J 0
(-2199 -625);
DISPLAY 0.638298 (-2199 -625);
PAINT MONO (-2199 -625);
FORCEPROP 2 LAST CDS_LIB standard
J 0
(-1975 -625);
PAINT MONO (-1975 -625);
DISPLAY INVISIBLE (-1975 -625);
FORCEPROP 1 LAST OFFPAGE TRUE
J 2
(-2300 -750);
DISPLAY 0.872340 (-2300 -750);
DISPLAY INVISIBLE (-2300 -750);
FORCEPROP 1 LAST COMMENT_BODY TRUE
J 2
(-1930 -720);
DISPLAY 0.872340 (-1930 -720);
PAINT GREEN (-1930 -720);
DISPLAY INVISIBLE (-1930 -720);
FORCEPROP 2 LAST PATH I1
J 0
(-1925 -550);
DISPLAY 1.021277 (-1925 -550);
DISPLAY INVISIBLE (-1925 -550);
FORCEADD OFFPAGE..3
R 2
(-1975 1950);
FORCEPROP 2 LAST $XR1 94 
J 0
(-2314 1950);
DISPLAY 0.638298 (-2314 1950);
PAINT MONO (-2314 1950);
FORCEPROP 2 LAST $XR0 26 
J 0
(-2224 1950);
DISPLAY 0.638298 (-2224 1950);
PAINT MONO (-2224 1950);
FORCEPROP 2 LAST CDS_LIB standard
J 0
(-1975 1950);
PAINT MONO (-1975 1950);
DISPLAY INVISIBLE (-1975 1950);
FORCEPROP 1 LAST OFFPAGE TRUE
J 2
(-2300 1825);
DISPLAY 0.872340 (-2300 1825);
DISPLAY INVISIBLE (-2300 1825);
FORCEPROP 1 LAST COMMENT_BODY TRUE
J 2
(-1925 1850);
DISPLAY 0.872340 (-1925 1850);
PAINT GREEN (-1925 1850);
DISPLAY INVISIBLE (-1925 1850);
FORCEPROP 2 LAST PATH I10
J 0
(-1925 2025);
DISPLAY 1.021277 (-1925 2025);
DISPLAY INVISIBLE (-1925 2025);
FORCEADD TAP..1
(600 2825);
FORCEPROP 3 LASTPIN (550 2825) SIG_NAME M_G_CPU0_SA_DQ<21>
J 0
(560 2835);
DISPLAY 0.659574 (560 2835);
PAINT MONO (560 2835);
DISPLAY INVISIBLE (560 2835);
FORCEPROP 1 LASTPIN (550 2825) BN 21
J 0
(538 2833);
DISPLAY 0.680851 (538 2833);
PAINT GREEN (538 2833);
FORCEPROP 2 LAST CDS_LIB standard
J 0
(600 2825);
PAINT MONO (600 2825);
DISPLAY INVISIBLE (600 2825);
FORCEPROP 1 LAST BODY_TYPE PLUMBING
J 0
(600 2875);
DISPLAY 0.872340 (600 2875);
PAINT GREEN (600 2875);
DISPLAY INVISIBLE (600 2875);
FORCEPROP 1 LAST HDL_TAP TRUE
J 0
(925 2700);
DISPLAY 0.872340 (925 2700);
DISPLAY INVISIBLE (925 2700);
FORCEPROP 1 LAST PATH I100
J 0
(598 2825);
DISPLAY 0.872340 (598 2825);
PAINT GREEN (598 2825);
DISPLAY INVISIBLE (598 2825);
FORCEADD TAP..1
(600 2775);
FORCEPROP 3 LASTPIN (550 2775) SIG_NAME M_G_CPU0_SA_DQ<20>
J 0
(560 2785);
DISPLAY 0.659574 (560 2785);
PAINT MONO (560 2785);
DISPLAY INVISIBLE (560 2785);
FORCEPROP 1 LASTPIN (550 2775) BN 20
J 0
(538 2783);
DISPLAY 0.680851 (538 2783);
PAINT GREEN (538 2783);
FORCEPROP 2 LAST CDS_LIB standard
J 0
(600 2775);
PAINT MONO (600 2775);
DISPLAY INVISIBLE (600 2775);
FORCEPROP 1 LAST BODY_TYPE PLUMBING
J 0
(600 2825);
DISPLAY 0.872340 (600 2825);
PAINT GREEN (600 2825);
DISPLAY INVISIBLE (600 2825);
FORCEPROP 1 LAST HDL_TAP TRUE
J 0
(925 2650);
DISPLAY 0.872340 (925 2650);
DISPLAY INVISIBLE (925 2650);
FORCEPROP 1 LAST PATH I101
J 0
(598 2775);
DISPLAY 0.872340 (598 2775);
PAINT GREEN (598 2775);
DISPLAY INVISIBLE (598 2775);
FORCEADD TAP..1
(600 2875);
FORCEPROP 3 LASTPIN (550 2875) SIG_NAME M_G_CPU0_SA_DQ<22>
J 0
(560 2885);
DISPLAY 0.659574 (560 2885);
PAINT MONO (560 2885);
DISPLAY INVISIBLE (560 2885);
FORCEPROP 1 LASTPIN (550 2875) BN 22
J 0
(538 2883);
DISPLAY 0.680851 (538 2883);
PAINT GREEN (538 2883);
FORCEPROP 2 LAST CDS_LIB standard
J 0
(600 2875);
DISPLAY INVISIBLE (600 2875);
FORCEPROP 1 LAST BODY_TYPE PLUMBING
J 0
(600 2925);
DISPLAY 0.872340 (600 2925);
PAINT GREEN (600 2925);
DISPLAY INVISIBLE (600 2925);
FORCEPROP 1 LAST HDL_TAP TRUE
J 0
(925 2750);
DISPLAY 0.872340 (925 2750);
DISPLAY INVISIBLE (925 2750);
FORCEPROP 1 LAST PATH I102
J 0
(598 2875);
DISPLAY 0.872340 (598 2875);
PAINT GREEN (598 2875);
DISPLAY INVISIBLE (598 2875);
FORCEADD TAP..1
(600 2925);
FORCEPROP 3 LASTPIN (550 2925) SIG_NAME M_G_CPU0_SA_DQ<23>
J 0
(560 2935);
DISPLAY 0.659574 (560 2935);
PAINT MONO (560 2935);
DISPLAY INVISIBLE (560 2935);
FORCEPROP 1 LASTPIN (550 2925) BN 23
J 0
(538 2933);
DISPLAY 0.680851 (538 2933);
PAINT GREEN (538 2933);
FORCEPROP 2 LAST CDS_LIB standard
J 0
(600 2925);
DISPLAY INVISIBLE (600 2925);
FORCEPROP 1 LAST BODY_TYPE PLUMBING
J 0
(600 2975);
DISPLAY 0.872340 (600 2975);
PAINT GREEN (600 2975);
DISPLAY INVISIBLE (600 2975);
FORCEPROP 1 LAST HDL_TAP TRUE
J 0
(925 2800);
DISPLAY 0.872340 (925 2800);
DISPLAY INVISIBLE (925 2800);
FORCEPROP 1 LAST PATH I103
J 0
(598 2925);
DISPLAY 0.872340 (598 2925);
PAINT GREEN (598 2925);
DISPLAY INVISIBLE (598 2925);
FORCEADD TAP..1
(600 2975);
FORCEPROP 3 LASTPIN (550 2975) SIG_NAME M_G_CPU0_SA_DQ<24>
J 0
(560 2985);
DISPLAY 0.659574 (560 2985);
PAINT MONO (560 2985);
DISPLAY INVISIBLE (560 2985);
FORCEPROP 1 LASTPIN (550 2975) BN 24
J 0
(538 2983);
DISPLAY 0.680851 (538 2983);
PAINT GREEN (538 2983);
FORCEPROP 2 LAST CDS_LIB standard
J 0
(600 2975);
DISPLAY INVISIBLE (600 2975);
FORCEPROP 1 LAST BODY_TYPE PLUMBING
J 0
(600 3025);
DISPLAY 0.872340 (600 3025);
PAINT GREEN (600 3025);
DISPLAY INVISIBLE (600 3025);
FORCEPROP 1 LAST HDL_TAP TRUE
J 0
(925 2850);
DISPLAY 0.872340 (925 2850);
DISPLAY INVISIBLE (925 2850);
FORCEPROP 1 LAST PATH I104
J 0
(598 2975);
DISPLAY 0.872340 (598 2975);
PAINT GREEN (598 2975);
DISPLAY INVISIBLE (598 2975);
FORCEADD OFFPAGE..1
(-1975 3350);
FORCEPROP 2 LAST $XR1 94 
J 0
(-2286 3350);
DISPLAY 0.638298 (-2286 3350);
PAINT MONO (-2286 3350);
FORCEPROP 2 LAST $XR0 26 
J 0
(-2196 3350);
DISPLAY 0.638298 (-2196 3350);
PAINT MONO (-2196 3350);
FORCEPROP 2 LAST CDS_LIB standard
J 0
(-1975 3350);
PAINT MONO (-1975 3350);
DISPLAY INVISIBLE (-1975 3350);
FORCEPROP 1 LAST OFFPAGE TRUE
J 0
(-1650 3225);
DISPLAY 0.872340 (-1650 3225);
DISPLAY INVISIBLE (-1650 3225);
FORCEPROP 1 LAST COMMENT_BODY TRUE
J 0
(-1850 3250);
DISPLAY 0.872340 (-1850 3250);
PAINT GREEN (-1850 3250);
DISPLAY INVISIBLE (-1850 3250);
FORCEPROP 2 LAST PATH I105
J 0
(-1925 3425);
DISPLAY 1.021277 (-1925 3425);
DISPLAY INVISIBLE (-1925 3425);
FORCEADD TAP..1
R 2
(-1050 3075);
FORCEPROP 3 LASTPIN (-1000 3075) SIG_NAME M_G_CPU0_SA_CA<1>
J 0
(-990 3085);
DISPLAY 0.659574 (-990 3085);
PAINT MONO (-990 3085);
DISPLAY INVISIBLE (-990 3085);
FORCEPROP 1 LASTPIN (-1000 3075) BN 1
J 2
(-988 3083);
DISPLAY 0.680851 (-988 3083);
PAINT GREEN (-988 3083);
FORCEPROP 2 LAST CDS_LIB standard
J 0
(-1050 3075);
DISPLAY INVISIBLE (-1050 3075);
FORCEPROP 1 LAST BODY_TYPE PLUMBING
J 2
(-1050 3125);
DISPLAY 0.872340 (-1050 3125);
PAINT GREEN (-1050 3125);
DISPLAY INVISIBLE (-1050 3125);
FORCEPROP 1 LAST HDL_TAP TRUE
J 2
(-1375 2950);
DISPLAY 0.872340 (-1375 2950);
DISPLAY INVISIBLE (-1375 2950);
FORCEPROP 1 LAST PATH I106
J 2
(-1048 3075);
DISPLAY 0.872340 (-1048 3075);
PAINT GREEN (-1048 3075);
DISPLAY INVISIBLE (-1048 3075);
FORCEADD TAP..1
R 2
(-1050 3025);
FORCEPROP 3 LASTPIN (-1000 3025) SIG_NAME M_G_CPU0_SA_CA<0>
J 0
(-990 3035);
DISPLAY 0.659574 (-990 3035);
PAINT MONO (-990 3035);
DISPLAY INVISIBLE (-990 3035);
FORCEPROP 1 LASTPIN (-1000 3025) BN 0
J 2
(-988 3033);
DISPLAY 0.680851 (-988 3033);
PAINT GREEN (-988 3033);
FORCEPROP 2 LAST CDS_LIB standard
J 0
(-1050 3025);
DISPLAY INVISIBLE (-1050 3025);
FORCEPROP 1 LAST BODY_TYPE PLUMBING
J 2
(-1050 3075);
DISPLAY 0.872340 (-1050 3075);
PAINT GREEN (-1050 3075);
DISPLAY INVISIBLE (-1050 3075);
FORCEPROP 1 LAST HDL_TAP TRUE
J 2
(-1375 2900);
DISPLAY 0.872340 (-1375 2900);
DISPLAY INVISIBLE (-1375 2900);
FORCEPROP 1 LAST PATH I107
J 2
(-1048 3025);
DISPLAY 0.872340 (-1048 3025);
PAINT GREEN (-1048 3025);
DISPLAY INVISIBLE (-1048 3025);
FORCEADD TAP..1
R 2
(-1050 3125);
FORCEPROP 3 LASTPIN (-1000 3125) SIG_NAME M_G_CPU0_SA_CA<2>
J 0
(-990 3135);
DISPLAY 0.659574 (-990 3135);
PAINT MONO (-990 3135);
DISPLAY INVISIBLE (-990 3135);
FORCEPROP 1 LASTPIN (-1000 3125) BN 2
J 2
(-988 3133);
DISPLAY 0.680851 (-988 3133);
PAINT GREEN (-988 3133);
FORCEPROP 2 LAST CDS_LIB standard
J 0
(-1050 3125);
DISPLAY INVISIBLE (-1050 3125);
FORCEPROP 1 LAST BODY_TYPE PLUMBING
J 2
(-1050 3175);
DISPLAY 0.872340 (-1050 3175);
PAINT GREEN (-1050 3175);
DISPLAY INVISIBLE (-1050 3175);
FORCEPROP 1 LAST HDL_TAP TRUE
J 2
(-1375 3000);
DISPLAY 0.872340 (-1375 3000);
DISPLAY INVISIBLE (-1375 3000);
FORCEPROP 1 LAST PATH I108
J 2
(-1048 3125);
DISPLAY 0.872340 (-1048 3125);
PAINT GREEN (-1048 3125);
DISPLAY INVISIBLE (-1048 3125);
FORCEADD TAP..1
R 2
(-1050 3225);
FORCEPROP 3 LASTPIN (-1000 3225) SIG_NAME M_G_CPU0_SA_CA<4>
J 0
(-990 3235);
DISPLAY 0.659574 (-990 3235);
PAINT MONO (-990 3235);
DISPLAY INVISIBLE (-990 3235);
FORCEPROP 1 LASTPIN (-1000 3225) BN 4
J 2
(-988 3233);
DISPLAY 0.680851 (-988 3233);
PAINT GREEN (-988 3233);
FORCEPROP 2 LAST CDS_LIB standard
J 0
(-1050 3225);
DISPLAY INVISIBLE (-1050 3225);
FORCEPROP 1 LAST BODY_TYPE PLUMBING
J 2
(-1050 3275);
DISPLAY 0.872340 (-1050 3275);
PAINT GREEN (-1050 3275);
DISPLAY INVISIBLE (-1050 3275);
FORCEPROP 1 LAST HDL_TAP TRUE
J 2
(-1375 3100);
DISPLAY 0.872340 (-1375 3100);
DISPLAY INVISIBLE (-1375 3100);
FORCEPROP 1 LAST PATH I109
J 2
(-1048 3225);
DISPLAY 0.872340 (-1048 3225);
PAINT GREEN (-1048 3225);
DISPLAY INVISIBLE (-1048 3225);
FORCEADD OFFPAGE..3
R 2
(-1975 1500);
FORCEPROP 2 LAST $XR1 94 
J 0
(-2314 1500);
DISPLAY 0.638298 (-2314 1500);
PAINT MONO (-2314 1500);
FORCEPROP 2 LAST $XR0 26 
J 0
(-2224 1500);
DISPLAY 0.638298 (-2224 1500);
PAINT MONO (-2224 1500);
FORCEPROP 2 LAST CDS_LIB standard
J 0
(-1975 1500);
PAINT MONO (-1975 1500);
DISPLAY INVISIBLE (-1975 1500);
FORCEPROP 1 LAST OFFPAGE TRUE
J 2
(-2300 1375);
DISPLAY 0.872340 (-2300 1375);
DISPLAY INVISIBLE (-2300 1375);
FORCEPROP 1 LAST COMMENT_BODY TRUE
J 2
(-1925 1400);
DISPLAY 0.872340 (-1925 1400);
PAINT GREEN (-1925 1400);
DISPLAY INVISIBLE (-1925 1400);
FORCEPROP 2 LAST PATH I11
J 0
(-1925 1575);
DISPLAY 1.021277 (-1925 1575);
DISPLAY INVISIBLE (-1925 1575);
FORCEADD TAP..1
R 2
(-1050 3175);
FORCEPROP 3 LASTPIN (-1000 3175) SIG_NAME M_G_CPU0_SA_CA<3>
J 0
(-990 3185);
DISPLAY 0.659574 (-990 3185);
PAINT MONO (-990 3185);
DISPLAY INVISIBLE (-990 3185);
FORCEPROP 1 LASTPIN (-1000 3175) BN 3
J 2
(-988 3183);
DISPLAY 0.680851 (-988 3183);
PAINT GREEN (-988 3183);
FORCEPROP 2 LAST CDS_LIB standard
J 0
(-1050 3175);
DISPLAY INVISIBLE (-1050 3175);
FORCEPROP 1 LAST BODY_TYPE PLUMBING
J 2
(-1050 3225);
DISPLAY 0.872340 (-1050 3225);
PAINT GREEN (-1050 3225);
DISPLAY INVISIBLE (-1050 3225);
FORCEPROP 1 LAST HDL_TAP TRUE
J 2
(-1375 3050);
DISPLAY 0.872340 (-1375 3050);
DISPLAY INVISIBLE (-1375 3050);
FORCEPROP 1 LAST PATH I110
J 2
(-1048 3175);
DISPLAY 0.872340 (-1048 3175);
PAINT GREEN (-1048 3175);
DISPLAY INVISIBLE (-1048 3175);
FORCEADD TAP..1
R 2
(-1050 3325);
FORCEPROP 3 LASTPIN (-1000 3325) SIG_NAME M_G_CPU0_SA_CA<6>
J 0
(-990 3335);
DISPLAY 0.659574 (-990 3335);
PAINT MONO (-990 3335);
DISPLAY INVISIBLE (-990 3335);
FORCEPROP 1 LASTPIN (-1000 3325) BN 6
J 2
(-988 3333);
DISPLAY 0.680851 (-988 3333);
PAINT GREEN (-988 3333);
FORCEPROP 2 LAST CDS_LIB standard
J 0
(-1050 3325);
DISPLAY INVISIBLE (-1050 3325);
FORCEPROP 1 LAST BODY_TYPE PLUMBING
J 2
(-1050 3375);
DISPLAY 0.872340 (-1050 3375);
PAINT GREEN (-1050 3375);
DISPLAY INVISIBLE (-1050 3375);
FORCEPROP 1 LAST HDL_TAP TRUE
J 2
(-1375 3200);
DISPLAY 0.872340 (-1375 3200);
DISPLAY INVISIBLE (-1375 3200);
FORCEPROP 1 LAST PATH I111
J 2
(-1048 3325);
DISPLAY 0.872340 (-1048 3325);
PAINT GREEN (-1048 3325);
DISPLAY INVISIBLE (-1048 3325);
FORCEADD TAP..1
R 2
(-1050 3275);
FORCEPROP 3 LASTPIN (-1000 3275) SIG_NAME M_G_CPU0_SA_CA<5>
J 0
(-990 3285);
DISPLAY 0.659574 (-990 3285);
PAINT MONO (-990 3285);
DISPLAY INVISIBLE (-990 3285);
FORCEPROP 1 LASTPIN (-1000 3275) BN 5
J 2
(-988 3283);
DISPLAY 0.680851 (-988 3283);
PAINT GREEN (-988 3283);
FORCEPROP 2 LAST CDS_LIB standard
J 0
(-1050 3275);
DISPLAY INVISIBLE (-1050 3275);
FORCEPROP 1 LAST BODY_TYPE PLUMBING
J 2
(-1050 3325);
DISPLAY 0.872340 (-1050 3325);
PAINT GREEN (-1050 3325);
DISPLAY INVISIBLE (-1050 3325);
FORCEPROP 1 LAST HDL_TAP TRUE
J 2
(-1375 3150);
DISPLAY 0.872340 (-1375 3150);
DISPLAY INVISIBLE (-1375 3150);
FORCEPROP 1 LAST PATH I112
J 2
(-1048 3275);
DISPLAY 0.872340 (-1048 3275);
PAINT GREEN (-1048 3275);
DISPLAY INVISIBLE (-1048 3275);
FORCEADD TAP..1
(600 3075);
FORCEPROP 3 LASTPIN (550 3075) SIG_NAME M_G_CPU0_SA_DQ<26>
J 0
(560 3085);
DISPLAY 0.659574 (560 3085);
PAINT MONO (560 3085);
DISPLAY INVISIBLE (560 3085);
FORCEPROP 1 LASTPIN (550 3075) BN 26
J 0
(538 3083);
DISPLAY 0.680851 (538 3083);
PAINT GREEN (538 3083);
FORCEPROP 2 LAST CDS_LIB standard
J 0
(600 3075);
DISPLAY INVISIBLE (600 3075);
FORCEPROP 1 LAST BODY_TYPE PLUMBING
J 0
(600 3125);
DISPLAY 0.872340 (600 3125);
PAINT GREEN (600 3125);
DISPLAY INVISIBLE (600 3125);
FORCEPROP 1 LAST HDL_TAP TRUE
J 0
(925 2950);
DISPLAY 0.872340 (925 2950);
DISPLAY INVISIBLE (925 2950);
FORCEPROP 1 LAST PATH I113
J 0
(598 3075);
DISPLAY 0.872340 (598 3075);
PAINT GREEN (598 3075);
DISPLAY INVISIBLE (598 3075);
FORCEADD TAP..1
(600 3025);
FORCEPROP 3 LASTPIN (550 3025) SIG_NAME M_G_CPU0_SA_DQ<25>
J 0
(560 3035);
DISPLAY 0.659574 (560 3035);
PAINT MONO (560 3035);
DISPLAY INVISIBLE (560 3035);
FORCEPROP 1 LASTPIN (550 3025) BN 25
J 0
(538 3033);
DISPLAY 0.680851 (538 3033);
PAINT GREEN (538 3033);
FORCEPROP 2 LAST CDS_LIB standard
J 0
(600 3025);
DISPLAY INVISIBLE (600 3025);
FORCEPROP 1 LAST BODY_TYPE PLUMBING
J 0
(600 3075);
DISPLAY 0.872340 (600 3075);
PAINT GREEN (600 3075);
DISPLAY INVISIBLE (600 3075);
FORCEPROP 1 LAST HDL_TAP TRUE
J 0
(925 2900);
DISPLAY 0.872340 (925 2900);
DISPLAY INVISIBLE (925 2900);
FORCEPROP 1 LAST PATH I114
J 0
(598 3025);
DISPLAY 0.872340 (598 3025);
PAINT GREEN (598 3025);
DISPLAY INVISIBLE (598 3025);
FORCEADD TAP..1
(600 3175);
FORCEPROP 3 LASTPIN (550 3175) SIG_NAME M_G_CPU0_SA_DQ<28>
J 0
(560 3185);
DISPLAY 0.659574 (560 3185);
PAINT MONO (560 3185);
DISPLAY INVISIBLE (560 3185);
FORCEPROP 1 LASTPIN (550 3175) BN 28
J 0
(538 3183);
DISPLAY 0.680851 (538 3183);
PAINT GREEN (538 3183);
FORCEPROP 2 LAST CDS_LIB standard
J 0
(600 3175);
DISPLAY INVISIBLE (600 3175);
FORCEPROP 1 LAST BODY_TYPE PLUMBING
J 0
(600 3225);
DISPLAY 0.872340 (600 3225);
PAINT GREEN (600 3225);
DISPLAY INVISIBLE (600 3225);
FORCEPROP 1 LAST HDL_TAP TRUE
J 0
(925 3050);
DISPLAY 0.872340 (925 3050);
DISPLAY INVISIBLE (925 3050);
FORCEPROP 1 LAST PATH I115
J 0
(598 3175);
DISPLAY 0.872340 (598 3175);
PAINT GREEN (598 3175);
DISPLAY INVISIBLE (598 3175);
FORCEADD TAP..1
(600 3225);
FORCEPROP 3 LASTPIN (550 3225) SIG_NAME M_G_CPU0_SA_DQ<29>
J 0
(560 3235);
DISPLAY 0.659574 (560 3235);
PAINT MONO (560 3235);
DISPLAY INVISIBLE (560 3235);
FORCEPROP 1 LASTPIN (550 3225) BN 29
J 0
(538 3233);
DISPLAY 0.680851 (538 3233);
PAINT GREEN (538 3233);
FORCEPROP 2 LAST CDS_LIB standard
J 0
(600 3225);
DISPLAY INVISIBLE (600 3225);
FORCEPROP 1 LAST BODY_TYPE PLUMBING
J 0
(600 3275);
DISPLAY 0.872340 (600 3275);
PAINT GREEN (600 3275);
DISPLAY INVISIBLE (600 3275);
FORCEPROP 1 LAST HDL_TAP TRUE
J 0
(925 3100);
DISPLAY 0.872340 (925 3100);
DISPLAY INVISIBLE (925 3100);
FORCEPROP 1 LAST PATH I116
J 0
(598 3225);
DISPLAY 0.872340 (598 3225);
PAINT GREEN (598 3225);
DISPLAY INVISIBLE (598 3225);
FORCEADD TAP..1
(600 3125);
FORCEPROP 3 LASTPIN (550 3125) SIG_NAME M_G_CPU0_SA_DQ<27>
J 0
(560 3135);
DISPLAY 0.659574 (560 3135);
PAINT MONO (560 3135);
DISPLAY INVISIBLE (560 3135);
FORCEPROP 1 LASTPIN (550 3125) BN 27
J 0
(538 3133);
DISPLAY 0.680851 (538 3133);
PAINT GREEN (538 3133);
FORCEPROP 2 LAST CDS_LIB standard
J 0
(600 3125);
DISPLAY INVISIBLE (600 3125);
FORCEPROP 1 LAST BODY_TYPE PLUMBING
J 0
(600 3175);
DISPLAY 0.872340 (600 3175);
PAINT GREEN (600 3175);
DISPLAY INVISIBLE (600 3175);
FORCEPROP 1 LAST HDL_TAP TRUE
J 0
(925 3000);
DISPLAY 0.872340 (925 3000);
DISPLAY INVISIBLE (925 3000);
FORCEPROP 1 LAST PATH I117
J 0
(598 3125);
DISPLAY 0.872340 (598 3125);
PAINT GREEN (598 3125);
DISPLAY INVISIBLE (598 3125);
FORCEADD TAP..1
(600 3275);
FORCEPROP 3 LASTPIN (550 3275) SIG_NAME M_G_CPU0_SA_DQ<30>
J 0
(560 3285);
DISPLAY 0.659574 (560 3285);
PAINT MONO (560 3285);
DISPLAY INVISIBLE (560 3285);
FORCEPROP 1 LASTPIN (550 3275) BN 30
J 0
(538 3283);
DISPLAY 0.680851 (538 3283);
PAINT GREEN (538 3283);
FORCEPROP 2 LAST CDS_LIB standard
J 0
(600 3275);
DISPLAY INVISIBLE (600 3275);
FORCEPROP 1 LAST BODY_TYPE PLUMBING
J 0
(600 3325);
DISPLAY 0.872340 (600 3325);
PAINT GREEN (600 3325);
DISPLAY INVISIBLE (600 3325);
FORCEPROP 1 LAST HDL_TAP TRUE
J 0
(925 3150);
DISPLAY 0.872340 (925 3150);
DISPLAY INVISIBLE (925 3150);
FORCEPROP 1 LAST PATH I118
J 0
(598 3275);
DISPLAY 0.872340 (598 3275);
PAINT GREEN (598 3275);
DISPLAY INVISIBLE (598 3275);
FORCEADD TAP..1
(600 3325);
FORCEPROP 3 LASTPIN (550 3325) SIG_NAME M_G_CPU0_SA_DQ<31>
J 0
(560 3335);
DISPLAY 0.659574 (560 3335);
PAINT MONO (560 3335);
DISPLAY INVISIBLE (560 3335);
FORCEPROP 1 LASTPIN (550 3325) BN 31
J 0
(538 3333);
DISPLAY 0.680851 (538 3333);
PAINT GREEN (538 3333);
FORCEPROP 2 LAST CDS_LIB standard
J 0
(600 3325);
DISPLAY INVISIBLE (600 3325);
FORCEPROP 1 LAST BODY_TYPE PLUMBING
J 0
(600 3375);
DISPLAY 0.872340 (600 3375);
PAINT GREEN (600 3375);
DISPLAY INVISIBLE (600 3375);
FORCEPROP 1 LAST HDL_TAP TRUE
J 0
(925 3200);
DISPLAY 0.872340 (925 3200);
DISPLAY INVISIBLE (925 3200);
FORCEPROP 1 LAST PATH I119
J 0
(598 3325);
DISPLAY 0.872340 (598 3325);
PAINT GREEN (598 3325);
DISPLAY INVISIBLE (598 3325);
FORCEADD OFFPAGE..1
(-1975 2175);
FORCEPROP 2 LAST $XR0 26 
J 0
(-2196 2175);
DISPLAY 0.638298 (-2196 2175);
PAINT MONO (-2196 2175);
FORCEPROP 2 LAST CDS_LIB standard
J 0
(-1975 2175);
PAINT MONO (-1975 2175);
DISPLAY INVISIBLE (-1975 2175);
FORCEPROP 1 LAST OFFPAGE TRUE
J 0
(-1650 2050);
DISPLAY 0.872340 (-1650 2050);
DISPLAY INVISIBLE (-1650 2050);
FORCEPROP 1 LAST COMMENT_BODY TRUE
J 0
(-1850 2075);
DISPLAY 0.872340 (-1850 2075);
PAINT GREEN (-1850 2075);
DISPLAY INVISIBLE (-1850 2075);
FORCEPROP 2 LAST PATH I12
J 0
(-1925 2250);
DISPLAY 1.021277 (-1925 2250);
DISPLAY INVISIBLE (-1925 2250);
FORCEADD UNIVERSAL_GND..1
(2325 -925);
FORCEPROP 3 LASTPIN (2325 -875) SIG_NAME GND\g
J 0
(2335 -865);
DISPLAY 0.659574 (2335 -865);
PAINT MONO (2335 -865);
DISPLAY INVISIBLE (2335 -865);
FORCEPROP 2 LAST CDS_LIB logical_power
J 0
(2325 -925);
PAINT MONO (2325 -925);
DISPLAY INVISIBLE (2325 -925);
FORCEPROP 1 LAST HDL_POWER GND
J 1
(2350 -1000);
DISPLAY 0.872340 (2350 -1000);
PAINT GREEN (2350 -1000);
DISPLAY INVISIBLE (2350 -1000);
FORCEPROP 1 LAST PATH I120
J 0
(2400 -925);
DISPLAY 0.872340 (2400 -925);
PAINT AQUA (2400 -925);
DISPLAY INVISIBLE (2400 -925);
FORCEADD Q_CAP..1
(2325 -550);
FORCEPROP 1 LAST PART_NUMBER CH5221MEB00
J 0
(2375 -700);
DISPLAY 0.978723 (2375 -700);
DISPLAY INVISIBLE (2375 -700);
FORCEPROP 1 LAST MATERIAL X6S
J 0
(2375 -650);
DISPLAY 0.978723 (2375 -650);
FORCEPROP 1 LAST TOLERANCE 20%
J 0
(2375 -600);
DISPLAY 0.978723 (2375 -600);
FORCEPROP 1 LAST VOLTAGE 6.3V
J 0
(2375 -550);
DISPLAY 0.978723 (2375 -550);
FORCEPROP 1 LAST VALUE 2.2UF
J 0
(2375 -500);
DISPLAY 0.978723 (2375 -500);
FORCEPROP 1 LAST PACK_TYPE C0402
J 0
(2375 -750);
DISPLAY 0.978723 (2375 -750);
FORCEPROP 1 LAST $LOCATION C41
J 0
(2375 -450);
DISPLAY 0.978723 (2375 -450);
FORCEPROP 1 LASTPIN (2325 -450) $PN 1
J 0
(2335 -470);
DISPLAY 0.787234 (2335 -470);
FORCEPROP 1 LASTPIN (2325 -650) $PN 2
J 0
(2335 -670);
DISPLAY 0.787234 (2335 -670);
FORCEPROP 2 LAST CDS_LIB pure_quanta
J 0
(2325 -550);
PAINT MONO (2325 -550);
DISPLAY INVISIBLE (2325 -550);
FORCEPROP 2 LAST CDS_LOCATION C41
J 0
(2375 -350);
DISPLAY 1.021277 (2375 -350);
DISPLAY INVISIBLE (2375 -350);
FORCEPROP 2 LAST $SEC 1
J 0
(2375 -350);
DISPLAY 0.680851 (2375 -350);
PAINT MONO (2375 -350);
DISPLAY INVISIBLE (2375 -350);
FORCEPROP 2 LAST CDS_SEC 1
J 0
(2375 -350);
DISPLAY 1.021277 (2375 -350);
DISPLAY INVISIBLE (2375 -350);
FORCEPROP 1 LAST PATH I121
J 0
(2375 -400);
DISPLAY 0.978723 (2375 -400);
PAINT WHITE (2375 -400);
DISPLAY INVISIBLE (2375 -400);
FORCEADD VCC_CORE..1
(2325 -225);
FORCEPROP 3 LASTPIN (2325 -275) SIG_NAME P3V3_AUX\g
J 0
(2335 -265);
DISPLAY 0.659574 (2335 -265);
PAINT MONO (2335 -265);
DISPLAY INVISIBLE (2335 -265);
FORCEPROP 1 LAST HDL_POWER P3V3_AUX
J 1
(2325 -175);
DISPLAY 1.148936 (2325 -175);
PAINT GREEN (2325 -175);
FORCEPROP 2 LAST CDS_LIB logical_power
J 0
(2325 -225);
PAINT MONO (2325 -225);
DISPLAY INVISIBLE (2325 -225);
FORCEPROP 1 LAST PATH I122
J 0
(2375 -200);
DISPLAY 0.872340 (2375 -200);
PAINT AQUA (2375 -200);
DISPLAY INVISIBLE (2375 -200);
FORCEADD OFFPAGE..3
(1425 1700);
FORCEPROP 2 LAST $XR1 94 
J 0
(1729 1700);
DISPLAY 0.638298 (1729 1700);
PAINT MONO (1729 1700);
FORCEPROP 2 LAST $XR0 26 
J 0
(1639 1700);
DISPLAY 0.638298 (1639 1700);
PAINT MONO (1639 1700);
FORCEPROP 2 LAST CDS_LIB standard
J 2
(1425 1700);
DISPLAY INVISIBLE (1425 1700);
FORCEPROP 1 LAST OFFPAGE TRUE
J 0
(1750 1575);
DISPLAY 0.872340 (1750 1575);
DISPLAY INVISIBLE (1750 1575);
FORCEPROP 1 LAST COMMENT_BODY TRUE
J 0
(1375 1600);
DISPLAY 0.872340 (1375 1600);
PAINT GREEN (1375 1600);
DISPLAY INVISIBLE (1375 1600);
FORCEPROP 2 LAST PATH I123
J 0
(1625 1775);
DISPLAY 1.021277 (1625 1775);
DISPLAY INVISIBLE (1625 1775);
FORCEADD Q_CAP..1
(3325 -550);
FORCEPROP 1 LAST PART_NUMBER CH6103KEA00
J 0
(3375 -700);
DISPLAY 0.978723 (3375 -700);
DISPLAY INVISIBLE (3375 -700);
FORCEPROP 1 LAST TOLERANCE 10%
J 0
(3375 -600);
DISPLAY 0.978723 (3375 -600);
FORCEPROP 1 LAST VOLTAGE 16V
J 0
(3375 -550);
DISPLAY 0.978723 (3375 -550);
FORCEPROP 1 LAST VALUE 10UF
J 0
(3375 -500);
DISPLAY 0.978723 (3375 -500);
FORCEPROP 1 LAST PACK_TYPE C0805
J 0
(3375 -750);
DISPLAY 0.978723 (3375 -750);
FORCEPROP 1 LAST MATERIAL X6S
J 0
(3375 -650);
DISPLAY 0.978723 (3375 -650);
FORCEPROP 1 LAST $LOCATION C42
J 0
(3375 -450);
DISPLAY 0.978723 (3375 -450);
FORCEPROP 1 LASTPIN (3325 -450) $PN 1
J 0
(3335 -470);
DISPLAY 0.787234 (3335 -470);
FORCEPROP 1 LASTPIN (3325 -650) $PN 2
J 0
(3335 -670);
DISPLAY 0.787234 (3335 -670);
FORCEPROP 2 LAST CDS_LIB pure_quanta
J 0
(3325 -550);
PAINT MONO (3325 -550);
DISPLAY INVISIBLE (3325 -550);
FORCEPROP 2 LAST CDS_LOCATION C42
J 0
(3375 -350);
DISPLAY 1.021277 (3375 -350);
DISPLAY INVISIBLE (3375 -350);
FORCEPROP 2 LAST $SEC 1
J 0
(3375 -350);
DISPLAY 0.680851 (3375 -350);
PAINT MONO (3375 -350);
DISPLAY INVISIBLE (3375 -350);
FORCEPROP 2 LAST CDS_SEC 1
J 0
(3375 -350);
DISPLAY 1.021277 (3375 -350);
DISPLAY INVISIBLE (3375 -350);
FORCEPROP 1 LAST PATH I125
J 0
(3375 -400);
DISPLAY 0.978723 (3375 -400);
PAINT WHITE (3375 -400);
DISPLAY INVISIBLE (3375 -400);
FORCEADD VCC_CORE..1
(3325 -225);
FORCEPROP 3 LASTPIN (3325 -275) SIG_NAME P12V_S3_AUX_CPU0_NVDIMM\g
J 0
(3335 -265);
DISPLAY 0.659574 (3335 -265);
PAINT MONO (3335 -265);
DISPLAY INVISIBLE (3335 -265);
FORCEPROP 1 LAST HDL_POWER P12V_S3_AUX_CPU0_NVDIMM
J 1
(3325 -175);
DISPLAY 1.148936 (3325 -175);
PAINT GREEN (3325 -175);
FORCEPROP 2 LAST CDS_LIB logical_power
J 0
(3325 -225);
PAINT MONO (3325 -225);
DISPLAY INVISIBLE (3325 -225);
FORCEPROP 1 LAST PATH I126
J 0
(3375 -200);
DISPLAY 0.872340 (3375 -200);
PAINT AQUA (3375 -200);
DISPLAY INVISIBLE (3375 -200);
FORCEADD UNIVERSAL_GND..1
(3950 -925);
FORCEPROP 3 LASTPIN (3950 -875) SIG_NAME GND\g
J 0
(3960 -865);
DISPLAY 0.659574 (3960 -865);
PAINT MONO (3960 -865);
DISPLAY INVISIBLE (3960 -865);
FORCEPROP 2 LAST CDS_LIB logical_power
J 0
(3950 -925);
PAINT MONO (3950 -925);
DISPLAY INVISIBLE (3950 -925);
FORCEPROP 1 LAST HDL_POWER GND
J 1
(3975 -1000);
DISPLAY 0.872340 (3975 -1000);
PAINT GREEN (3975 -1000);
DISPLAY INVISIBLE (3975 -1000);
FORCEPROP 1 LAST PATH I127
J 0
(4025 -925);
DISPLAY 0.872340 (4025 -925);
PAINT AQUA (4025 -925);
DISPLAY INVISIBLE (4025 -925);
FORCEADD Q_CAP..1
(3950 -550);
FORCEPROP 1 LAST PART_NUMBER CH6103KEA00
J 0
(4000 -700);
DISPLAY 0.978723 (4000 -700);
DISPLAY INVISIBLE (4000 -700);
FORCEPROP 1 LAST TOLERANCE 10%
J 0
(4000 -600);
DISPLAY 0.978723 (4000 -600);
FORCEPROP 1 LAST VOLTAGE 16V
J 0
(4000 -550);
DISPLAY 0.978723 (4000 -550);
FORCEPROP 1 LAST VALUE 10UF
J 0
(4000 -500);
DISPLAY 0.978723 (4000 -500);
FORCEPROP 1 LAST PACK_TYPE C0805
J 0
(4000 -750);
DISPLAY 0.978723 (4000 -750);
FORCEPROP 1 LAST MATERIAL X6S
J 0
(4000 -650);
DISPLAY 0.978723 (4000 -650);
FORCEPROP 1 LAST $LOCATION C43
J 0
(4000 -450);
DISPLAY 0.978723 (4000 -450);
FORCEPROP 1 LASTPIN (3950 -450) $PN 1
J 0
(3960 -470);
DISPLAY 0.787234 (3960 -470);
FORCEPROP 1 LASTPIN (3950 -650) $PN 2
J 0
(3960 -670);
DISPLAY 0.787234 (3960 -670);
FORCEPROP 2 LAST CDS_LIB pure_quanta
J 0
(3950 -550);
PAINT MONO (3950 -550);
DISPLAY INVISIBLE (3950 -550);
FORCEPROP 2 LAST CDS_LOCATION C43
J 0
(4000 -350);
DISPLAY 1.021277 (4000 -350);
DISPLAY INVISIBLE (4000 -350);
FORCEPROP 2 LAST $SEC 1
J 0
(4000 -350);
DISPLAY 0.680851 (4000 -350);
PAINT MONO (4000 -350);
DISPLAY INVISIBLE (4000 -350);
FORCEPROP 2 LAST CDS_SEC 1
J 0
(4000 -350);
DISPLAY 1.021277 (4000 -350);
DISPLAY INVISIBLE (4000 -350);
FORCEPROP 1 LAST PATH I128
J 0
(4000 -400);
DISPLAY 0.978723 (4000 -400);
PAINT WHITE (4000 -400);
DISPLAY INVISIBLE (4000 -400);
FORCEADD UNIVERSAL_GND..1
(5025 -375);
FORCEPROP 3 LASTPIN (5025 -325) SIG_NAME GND\g
J 0
(5035 -315);
DISPLAY 0.659574 (5035 -315);
PAINT MONO (5035 -315);
DISPLAY INVISIBLE (5035 -315);
FORCEPROP 2 LAST CDS_LIB logical_power
J 0
(5025 -375);
PAINT MONO (5025 -375);
DISPLAY INVISIBLE (5025 -375);
FORCEPROP 1 LAST HDL_POWER GND
J 1
(5050 -450);
DISPLAY 0.872340 (5050 -450);
PAINT GREEN (5050 -450);
DISPLAY INVISIBLE (5050 -450);
FORCEPROP 1 LAST PATH I129
J 0
(5100 -375);
DISPLAY 0.872340 (5100 -375);
PAINT AQUA (5100 -375);
DISPLAY INVISIBLE (5100 -375);
FORCEADD OFFPAGE..1
(-1975 2075);
FORCEPROP 2 LAST $XR0 26 
J 0
(-2196 2075);
DISPLAY 0.638298 (-2196 2075);
PAINT MONO (-2196 2075);
FORCEPROP 2 LAST CDS_LIB standard
J 0
(-1975 2075);
PAINT MONO (-1975 2075);
DISPLAY INVISIBLE (-1975 2075);
FORCEPROP 1 LAST OFFPAGE TRUE
J 0
(-1650 1950);
DISPLAY 0.872340 (-1650 1950);
DISPLAY INVISIBLE (-1650 1950);
FORCEPROP 1 LAST COMMENT_BODY TRUE
J 0
(-1850 1975);
DISPLAY 0.872340 (-1850 1975);
PAINT GREEN (-1850 1975);
DISPLAY INVISIBLE (-1850 1975);
FORCEPROP 2 LAST PATH I13
J 0
(-1925 2150);
DISPLAY 1.021277 (-1925 2150);
DISPLAY INVISIBLE (-1925 2150);
FORCEADD TAP..1
(3375 1375);
FORCEPROP 3 LASTPIN (3325 1375) SIG_NAME M_G_CPU0_SB_DQS_DP<0>
J 0
(3335 1385);
DISPLAY 0.659574 (3335 1385);
PAINT MONO (3335 1385);
DISPLAY INVISIBLE (3335 1385);
FORCEPROP 1 LASTPIN (3325 1375) BN 0
J 0
(3313 1383);
DISPLAY 0.680851 (3313 1383);
PAINT GREEN (3313 1383);
FORCEPROP 2 LAST CDS_LIB standard
J 0
(3375 1375);
PAINT MONO (3375 1375);
DISPLAY INVISIBLE (3375 1375);
FORCEPROP 1 LAST BODY_TYPE PLUMBING
J 0
(3375 1425);
DISPLAY 0.872340 (3375 1425);
PAINT GREEN (3375 1425);
DISPLAY INVISIBLE (3375 1425);
FORCEPROP 1 LAST HDL_TAP TRUE
J 0
(3700 1250);
DISPLAY 0.872340 (3700 1250);
DISPLAY INVISIBLE (3700 1250);
FORCEPROP 1 LAST PATH I130
J 0
(3373 1375);
DISPLAY 0.872340 (3373 1375);
PAINT GREEN (3373 1375);
DISPLAY INVISIBLE (3373 1375);
FORCEADD TAP..1
(3550 1325);
FORCEPROP 3 LASTPIN (3500 1325) SIG_NAME M_G_CPU0_SB_DQS_DN<0>
J 0
(3510 1335);
DISPLAY 0.659574 (3510 1335);
PAINT MONO (3510 1335);
DISPLAY INVISIBLE (3510 1335);
FORCEPROP 1 LASTPIN (3500 1325) BN 0
J 0
(3488 1333);
DISPLAY 0.680851 (3488 1333);
PAINT GREEN (3488 1333);
FORCEPROP 2 LAST CDS_LIB standard
J 0
(3550 1325);
PAINT MONO (3550 1325);
DISPLAY INVISIBLE (3550 1325);
FORCEPROP 1 LAST BODY_TYPE PLUMBING
J 0
(3550 1375);
DISPLAY 0.872340 (3550 1375);
PAINT GREEN (3550 1375);
DISPLAY INVISIBLE (3550 1375);
FORCEPROP 1 LAST HDL_TAP TRUE
J 0
(3875 1200);
DISPLAY 0.872340 (3875 1200);
DISPLAY INVISIBLE (3875 1200);
FORCEPROP 1 LAST PATH I131
J 0
(3548 1325);
DISPLAY 0.872340 (3548 1325);
PAINT GREEN (3548 1325);
DISPLAY INVISIBLE (3548 1325);
FORCEADD TAP..1
(3550 1425);
FORCEPROP 3 LASTPIN (3500 1425) SIG_NAME M_G_CPU0_SB_DQS_DN<1>
J 0
(3510 1435);
DISPLAY 0.659574 (3510 1435);
PAINT MONO (3510 1435);
DISPLAY INVISIBLE (3510 1435);
FORCEPROP 1 LASTPIN (3500 1425) BN 1
J 0
(3488 1433);
DISPLAY 0.680851 (3488 1433);
PAINT GREEN (3488 1433);
FORCEPROP 2 LAST CDS_LIB standard
J 0
(3550 1425);
DISPLAY INVISIBLE (3550 1425);
FORCEPROP 1 LAST BODY_TYPE PLUMBING
J 0
(3550 1475);
DISPLAY 0.872340 (3550 1475);
PAINT GREEN (3550 1475);
DISPLAY INVISIBLE (3550 1475);
FORCEPROP 1 LAST HDL_TAP TRUE
J 0
(3875 1300);
DISPLAY 0.872340 (3875 1300);
DISPLAY INVISIBLE (3875 1300);
FORCEPROP 1 LAST PATH I132
J 0
(3548 1425);
DISPLAY 0.872340 (3548 1425);
PAINT GREEN (3548 1425);
DISPLAY INVISIBLE (3548 1425);
FORCEADD TAP..1
(3375 1475);
FORCEPROP 3 LASTPIN (3325 1475) SIG_NAME M_G_CPU0_SB_DQS_DP<1>
J 0
(3335 1485);
DISPLAY 0.659574 (3335 1485);
PAINT MONO (3335 1485);
DISPLAY INVISIBLE (3335 1485);
FORCEPROP 1 LASTPIN (3325 1475) BN 1
J 0
(3313 1483);
DISPLAY 0.680851 (3313 1483);
PAINT GREEN (3313 1483);
FORCEPROP 2 LAST CDS_LIB standard
J 0
(3375 1475);
DISPLAY INVISIBLE (3375 1475);
FORCEPROP 1 LAST BODY_TYPE PLUMBING
J 0
(3375 1525);
DISPLAY 0.872340 (3375 1525);
PAINT GREEN (3375 1525);
DISPLAY INVISIBLE (3375 1525);
FORCEPROP 1 LAST HDL_TAP TRUE
J 0
(3700 1350);
DISPLAY 0.872340 (3700 1350);
DISPLAY INVISIBLE (3700 1350);
FORCEPROP 1 LAST PATH I133
J 0
(3373 1475);
DISPLAY 0.872340 (3373 1475);
PAINT GREEN (3373 1475);
DISPLAY INVISIBLE (3373 1475);
FORCEADD TAP..1
(3375 1575);
FORCEPROP 3 LASTPIN (3325 1575) SIG_NAME M_G_CPU0_SB_DQS_DP<2>
J 0
(3335 1585);
DISPLAY 0.659574 (3335 1585);
PAINT MONO (3335 1585);
DISPLAY INVISIBLE (3335 1585);
FORCEPROP 1 LASTPIN (3325 1575) BN 2
J 0
(3313 1583);
DISPLAY 0.680851 (3313 1583);
PAINT GREEN (3313 1583);
FORCEPROP 2 LAST CDS_LIB standard
J 0
(3375 1575);
DISPLAY INVISIBLE (3375 1575);
FORCEPROP 1 LAST BODY_TYPE PLUMBING
J 0
(3375 1625);
DISPLAY 0.872340 (3375 1625);
PAINT GREEN (3375 1625);
DISPLAY INVISIBLE (3375 1625);
FORCEPROP 1 LAST HDL_TAP TRUE
J 0
(3700 1450);
DISPLAY 0.872340 (3700 1450);
DISPLAY INVISIBLE (3700 1450);
FORCEPROP 1 LAST PATH I134
J 0
(3373 1575);
DISPLAY 0.872340 (3373 1575);
PAINT GREEN (3373 1575);
DISPLAY INVISIBLE (3373 1575);
FORCEADD TAP..1
(3375 1675);
FORCEPROP 3 LASTPIN (3325 1675) SIG_NAME M_G_CPU0_SB_DQS_DP<3>
J 0
(3335 1685);
DISPLAY 0.659574 (3335 1685);
PAINT MONO (3335 1685);
DISPLAY INVISIBLE (3335 1685);
FORCEPROP 1 LASTPIN (3325 1675) BN 3
J 0
(3313 1683);
DISPLAY 0.680851 (3313 1683);
PAINT GREEN (3313 1683);
FORCEPROP 2 LAST CDS_LIB standard
J 0
(3375 1675);
PAINT MONO (3375 1675);
DISPLAY INVISIBLE (3375 1675);
FORCEPROP 1 LAST BODY_TYPE PLUMBING
J 0
(3375 1725);
DISPLAY 0.872340 (3375 1725);
PAINT GREEN (3375 1725);
DISPLAY INVISIBLE (3375 1725);
FORCEPROP 1 LAST HDL_TAP TRUE
J 0
(3700 1550);
DISPLAY 0.872340 (3700 1550);
DISPLAY INVISIBLE (3700 1550);
FORCEPROP 1 LAST PATH I135
J 0
(3373 1675);
DISPLAY 0.872340 (3373 1675);
PAINT GREEN (3373 1675);
DISPLAY INVISIBLE (3373 1675);
FORCEADD TAP..1
(3375 1775);
FORCEPROP 3 LASTPIN (3325 1775) SIG_NAME M_G_CPU0_SB_DQS_DP<4>
J 0
(3335 1785);
DISPLAY 0.659574 (3335 1785);
PAINT MONO (3335 1785);
DISPLAY INVISIBLE (3335 1785);
FORCEPROP 1 LASTPIN (3325 1775) BN 4
J 0
(3313 1783);
DISPLAY 0.680851 (3313 1783);
PAINT GREEN (3313 1783);
FORCEPROP 2 LAST CDS_LIB standard
J 0
(3375 1775);
PAINT MONO (3375 1775);
DISPLAY INVISIBLE (3375 1775);
FORCEPROP 1 LAST BODY_TYPE PLUMBING
J 0
(3375 1825);
DISPLAY 0.872340 (3375 1825);
PAINT GREEN (3375 1825);
DISPLAY INVISIBLE (3375 1825);
FORCEPROP 1 LAST HDL_TAP TRUE
J 0
(3700 1650);
DISPLAY 0.872340 (3700 1650);
DISPLAY INVISIBLE (3700 1650);
FORCEPROP 1 LAST PATH I136
J 0
(3373 1775);
DISPLAY 0.872340 (3373 1775);
PAINT GREEN (3373 1775);
DISPLAY INVISIBLE (3373 1775);
FORCEADD TAP..1
(3375 1875);
FORCEPROP 3 LASTPIN (3325 1875) SIG_NAME M_G_CPU0_SB_DQS_DP<5>
J 0
(3335 1885);
DISPLAY 0.659574 (3335 1885);
PAINT MONO (3335 1885);
DISPLAY INVISIBLE (3335 1885);
FORCEPROP 1 LASTPIN (3325 1875) BN 5
J 0
(3313 1883);
DISPLAY 0.680851 (3313 1883);
PAINT GREEN (3313 1883);
FORCEPROP 2 LAST CDS_LIB standard
J 0
(3375 1875);
DISPLAY INVISIBLE (3375 1875);
FORCEPROP 1 LAST BODY_TYPE PLUMBING
J 0
(3375 1925);
DISPLAY 0.872340 (3375 1925);
PAINT GREEN (3375 1925);
DISPLAY INVISIBLE (3375 1925);
FORCEPROP 1 LAST HDL_TAP TRUE
J 0
(3700 1750);
DISPLAY 0.872340 (3700 1750);
DISPLAY INVISIBLE (3700 1750);
FORCEPROP 1 LAST PATH I137
J 0
(3373 1875);
DISPLAY 0.872340 (3373 1875);
PAINT GREEN (3373 1875);
DISPLAY INVISIBLE (3373 1875);
FORCEADD TAP..1
(3550 1525);
FORCEPROP 3 LASTPIN (3500 1525) SIG_NAME M_G_CPU0_SB_DQS_DN<2>
J 0
(3510 1535);
DISPLAY 0.659574 (3510 1535);
PAINT MONO (3510 1535);
DISPLAY INVISIBLE (3510 1535);
FORCEPROP 1 LASTPIN (3500 1525) BN 2
J 0
(3488 1533);
DISPLAY 0.680851 (3488 1533);
PAINT GREEN (3488 1533);
FORCEPROP 2 LAST CDS_LIB standard
J 0
(3550 1525);
DISPLAY INVISIBLE (3550 1525);
FORCEPROP 1 LAST BODY_TYPE PLUMBING
J 0
(3550 1575);
DISPLAY 0.872340 (3550 1575);
PAINT GREEN (3550 1575);
DISPLAY INVISIBLE (3550 1575);
FORCEPROP 1 LAST HDL_TAP TRUE
J 0
(3875 1400);
DISPLAY 0.872340 (3875 1400);
DISPLAY INVISIBLE (3875 1400);
FORCEPROP 1 LAST PATH I138
J 0
(3548 1525);
DISPLAY 0.872340 (3548 1525);
PAINT GREEN (3548 1525);
DISPLAY INVISIBLE (3548 1525);
FORCEADD TAP..1
(3550 1625);
FORCEPROP 3 LASTPIN (3500 1625) SIG_NAME M_G_CPU0_SB_DQS_DN<3>
J 0
(3510 1635);
DISPLAY 0.659574 (3510 1635);
PAINT MONO (3510 1635);
DISPLAY INVISIBLE (3510 1635);
FORCEPROP 1 LASTPIN (3500 1625) BN 3
J 0
(3488 1633);
DISPLAY 0.680851 (3488 1633);
PAINT GREEN (3488 1633);
FORCEPROP 2 LAST CDS_LIB standard
J 0
(3550 1625);
PAINT MONO (3550 1625);
DISPLAY INVISIBLE (3550 1625);
FORCEPROP 1 LAST BODY_TYPE PLUMBING
J 0
(3550 1675);
DISPLAY 0.872340 (3550 1675);
PAINT GREEN (3550 1675);
DISPLAY INVISIBLE (3550 1675);
FORCEPROP 1 LAST HDL_TAP TRUE
J 0
(3875 1500);
DISPLAY 0.872340 (3875 1500);
DISPLAY INVISIBLE (3875 1500);
FORCEPROP 1 LAST PATH I139
J 0
(3548 1625);
DISPLAY 0.872340 (3548 1625);
PAINT GREEN (3548 1625);
DISPLAY INVISIBLE (3548 1625);
FORCEADD OFFPAGE..1
(-1975 2025);
FORCEPROP 2 LAST $XR0 26 
J 0
(-2196 2025);
DISPLAY 0.638298 (-2196 2025);
PAINT MONO (-2196 2025);
FORCEPROP 2 LAST CDS_LIB standard
J 0
(-1975 2025);
PAINT MONO (-1975 2025);
DISPLAY INVISIBLE (-1975 2025);
FORCEPROP 1 LAST OFFPAGE TRUE
J 0
(-1650 1900);
DISPLAY 0.872340 (-1650 1900);
DISPLAY INVISIBLE (-1650 1900);
FORCEPROP 1 LAST COMMENT_BODY TRUE
J 0
(-1850 1925);
DISPLAY 0.872340 (-1850 1925);
PAINT GREEN (-1850 1925);
DISPLAY INVISIBLE (-1850 1925);
FORCEPROP 2 LAST PATH I14
J 0
(-1925 2100);
DISPLAY 1.021277 (-1925 2100);
DISPLAY INVISIBLE (-1925 2100);
FORCEADD TAP..1
(3550 1725);
FORCEPROP 3 LASTPIN (3500 1725) SIG_NAME M_G_CPU0_SB_DQS_DN<4>
J 0
(3510 1735);
DISPLAY 0.659574 (3510 1735);
PAINT MONO (3510 1735);
DISPLAY INVISIBLE (3510 1735);
FORCEPROP 1 LASTPIN (3500 1725) BN 4
J 0
(3488 1733);
DISPLAY 0.680851 (3488 1733);
PAINT GREEN (3488 1733);
FORCEPROP 2 LAST CDS_LIB standard
J 0
(3550 1725);
PAINT MONO (3550 1725);
DISPLAY INVISIBLE (3550 1725);
FORCEPROP 1 LAST BODY_TYPE PLUMBING
J 0
(3550 1775);
DISPLAY 0.872340 (3550 1775);
PAINT GREEN (3550 1775);
DISPLAY INVISIBLE (3550 1775);
FORCEPROP 1 LAST HDL_TAP TRUE
J 0
(3875 1600);
DISPLAY 0.872340 (3875 1600);
DISPLAY INVISIBLE (3875 1600);
FORCEPROP 1 LAST PATH I140
J 0
(3548 1725);
DISPLAY 0.872340 (3548 1725);
PAINT GREEN (3548 1725);
DISPLAY INVISIBLE (3548 1725);
FORCEADD TAP..1
(3550 1825);
FORCEPROP 3 LASTPIN (3500 1825) SIG_NAME M_G_CPU0_SB_DQS_DN<5>
J 0
(3510 1835);
DISPLAY 0.659574 (3510 1835);
PAINT MONO (3510 1835);
DISPLAY INVISIBLE (3510 1835);
FORCEPROP 1 LASTPIN (3500 1825) BN 5
J 0
(3488 1833);
DISPLAY 0.680851 (3488 1833);
PAINT GREEN (3488 1833);
FORCEPROP 2 LAST CDS_LIB standard
J 0
(3550 1825);
DISPLAY INVISIBLE (3550 1825);
FORCEPROP 1 LAST BODY_TYPE PLUMBING
J 0
(3550 1875);
DISPLAY 0.872340 (3550 1875);
PAINT GREEN (3550 1875);
DISPLAY INVISIBLE (3550 1875);
FORCEPROP 1 LAST HDL_TAP TRUE
J 0
(3875 1700);
DISPLAY 0.872340 (3875 1700);
DISPLAY INVISIBLE (3875 1700);
FORCEPROP 1 LAST PATH I141
J 0
(3548 1825);
DISPLAY 0.872340 (3548 1825);
PAINT GREEN (3548 1825);
DISPLAY INVISIBLE (3548 1825);
FORCEADD TAP..1
(3550 1925);
FORCEPROP 3 LASTPIN (3500 1925) SIG_NAME M_G_CPU0_SB_DQS_DN<6>
J 0
(3510 1935);
DISPLAY 0.659574 (3510 1935);
PAINT MONO (3510 1935);
DISPLAY INVISIBLE (3510 1935);
FORCEPROP 1 LASTPIN (3500 1925) BN 6
J 0
(3488 1933);
DISPLAY 0.680851 (3488 1933);
PAINT GREEN (3488 1933);
FORCEPROP 2 LAST CDS_LIB standard
J 0
(3550 1925);
DISPLAY INVISIBLE (3550 1925);
FORCEPROP 1 LAST BODY_TYPE PLUMBING
J 0
(3550 1975);
DISPLAY 0.872340 (3550 1975);
PAINT GREEN (3550 1975);
DISPLAY INVISIBLE (3550 1975);
FORCEPROP 1 LAST HDL_TAP TRUE
J 0
(3875 1800);
DISPLAY 0.872340 (3875 1800);
DISPLAY INVISIBLE (3875 1800);
FORCEPROP 1 LAST PATH I142
J 0
(3548 1925);
DISPLAY 0.872340 (3548 1925);
PAINT GREEN (3548 1925);
DISPLAY INVISIBLE (3548 1925);
FORCEADD TAP..1
(3375 1975);
FORCEPROP 3 LASTPIN (3325 1975) SIG_NAME M_G_CPU0_SB_DQS_DP<6>
J 0
(3335 1985);
DISPLAY 0.659574 (3335 1985);
PAINT MONO (3335 1985);
DISPLAY INVISIBLE (3335 1985);
FORCEPROP 1 LASTPIN (3325 1975) BN 6
J 0
(3313 1983);
DISPLAY 0.680851 (3313 1983);
PAINT GREEN (3313 1983);
FORCEPROP 2 LAST CDS_LIB standard
J 0
(3375 1975);
DISPLAY INVISIBLE (3375 1975);
FORCEPROP 1 LAST BODY_TYPE PLUMBING
J 0
(3375 2025);
DISPLAY 0.872340 (3375 2025);
PAINT GREEN (3375 2025);
DISPLAY INVISIBLE (3375 2025);
FORCEPROP 1 LAST HDL_TAP TRUE
J 0
(3700 1850);
DISPLAY 0.872340 (3700 1850);
DISPLAY INVISIBLE (3700 1850);
FORCEPROP 1 LAST PATH I143
J 0
(3373 1975);
DISPLAY 0.872340 (3373 1975);
PAINT GREEN (3373 1975);
DISPLAY INVISIBLE (3373 1975);
FORCEADD TAP..1
(3375 2075);
FORCEPROP 3 LASTPIN (3325 2075) SIG_NAME M_G_CPU0_SB_DQS_DP<7>
J 0
(3335 2085);
DISPLAY 0.659574 (3335 2085);
PAINT MONO (3335 2085);
DISPLAY INVISIBLE (3335 2085);
FORCEPROP 1 LASTPIN (3325 2075) BN 7
J 0
(3313 2083);
DISPLAY 0.680851 (3313 2083);
PAINT GREEN (3313 2083);
FORCEPROP 2 LAST CDS_LIB standard
J 0
(3375 2075);
DISPLAY INVISIBLE (3375 2075);
FORCEPROP 1 LAST BODY_TYPE PLUMBING
J 0
(3375 2125);
DISPLAY 0.872340 (3375 2125);
PAINT GREEN (3375 2125);
DISPLAY INVISIBLE (3375 2125);
FORCEPROP 1 LAST HDL_TAP TRUE
J 0
(3700 1950);
DISPLAY 0.872340 (3700 1950);
DISPLAY INVISIBLE (3700 1950);
FORCEPROP 1 LAST PATH I144
J 0
(3373 2075);
DISPLAY 0.872340 (3373 2075);
PAINT GREEN (3373 2075);
DISPLAY INVISIBLE (3373 2075);
FORCEADD TAP..1
(3375 2175);
FORCEPROP 3 LASTPIN (3325 2175) SIG_NAME M_G_CPU0_SB_DQS_DP<8>
J 0
(3335 2185);
DISPLAY 0.659574 (3335 2185);
PAINT MONO (3335 2185);
DISPLAY INVISIBLE (3335 2185);
FORCEPROP 1 LASTPIN (3325 2175) BN 8
J 0
(3313 2183);
DISPLAY 0.680851 (3313 2183);
PAINT GREEN (3313 2183);
FORCEPROP 2 LAST CDS_LIB standard
J 0
(3375 2175);
DISPLAY INVISIBLE (3375 2175);
FORCEPROP 1 LAST BODY_TYPE PLUMBING
J 0
(3375 2225);
DISPLAY 0.872340 (3375 2225);
PAINT GREEN (3375 2225);
DISPLAY INVISIBLE (3375 2225);
FORCEPROP 1 LAST HDL_TAP TRUE
J 0
(3700 2050);
DISPLAY 0.872340 (3700 2050);
DISPLAY INVISIBLE (3700 2050);
FORCEPROP 1 LAST PATH I145
J 0
(3373 2175);
DISPLAY 0.872340 (3373 2175);
PAINT GREEN (3373 2175);
DISPLAY INVISIBLE (3373 2175);
FORCEADD TAP..1
(3375 2275);
FORCEPROP 3 LASTPIN (3325 2275) SIG_NAME M_G_CPU0_SB_DQS_DP<9>
J 0
(3335 2285);
DISPLAY 0.659574 (3335 2285);
PAINT MONO (3335 2285);
DISPLAY INVISIBLE (3335 2285);
FORCEPROP 1 LASTPIN (3325 2275) BN 9
J 0
(3313 2283);
DISPLAY 0.680851 (3313 2283);
PAINT GREEN (3313 2283);
FORCEPROP 2 LAST CDS_LIB standard
J 0
(3375 2275);
DISPLAY INVISIBLE (3375 2275);
FORCEPROP 1 LAST BODY_TYPE PLUMBING
J 0
(3375 2325);
DISPLAY 0.872340 (3375 2325);
PAINT GREEN (3375 2325);
DISPLAY INVISIBLE (3375 2325);
FORCEPROP 1 LAST HDL_TAP TRUE
J 0
(3700 2150);
DISPLAY 0.872340 (3700 2150);
DISPLAY INVISIBLE (3700 2150);
FORCEPROP 1 LAST PATH I146
J 0
(3373 2275);
DISPLAY 0.872340 (3373 2275);
PAINT GREEN (3373 2275);
DISPLAY INVISIBLE (3373 2275);
FORCEADD TAP..1
(3375 2425);
FORCEPROP 3 LASTPIN (3325 2425) SIG_NAME M_G_CPU0_SA_DQS_DP<0>
J 0
(3335 2435);
DISPLAY 0.659574 (3335 2435);
PAINT MONO (3335 2435);
DISPLAY INVISIBLE (3335 2435);
FORCEPROP 1 LASTPIN (3325 2425) BN 0
J 0
(3313 2433);
DISPLAY 0.680851 (3313 2433);
PAINT GREEN (3313 2433);
FORCEPROP 2 LAST CDS_LIB standard
J 0
(3375 2425);
PAINT MONO (3375 2425);
DISPLAY INVISIBLE (3375 2425);
FORCEPROP 1 LAST BODY_TYPE PLUMBING
J 0
(3375 2475);
DISPLAY 0.872340 (3375 2475);
PAINT GREEN (3375 2475);
DISPLAY INVISIBLE (3375 2475);
FORCEPROP 1 LAST HDL_TAP TRUE
J 0
(3700 2300);
DISPLAY 0.872340 (3700 2300);
DISPLAY INVISIBLE (3700 2300);
FORCEPROP 1 LAST PATH I147
J 0
(3373 2425);
DISPLAY 0.872340 (3373 2425);
PAINT GREEN (3373 2425);
DISPLAY INVISIBLE (3373 2425);
FORCEADD TAP..1
(3550 2025);
FORCEPROP 3 LASTPIN (3500 2025) SIG_NAME M_G_CPU0_SB_DQS_DN<7>
J 0
(3510 2035);
DISPLAY 0.659574 (3510 2035);
PAINT MONO (3510 2035);
DISPLAY INVISIBLE (3510 2035);
FORCEPROP 1 LASTPIN (3500 2025) BN 7
J 0
(3488 2033);
DISPLAY 0.680851 (3488 2033);
PAINT GREEN (3488 2033);
FORCEPROP 2 LAST CDS_LIB standard
J 0
(3550 2025);
DISPLAY INVISIBLE (3550 2025);
FORCEPROP 1 LAST BODY_TYPE PLUMBING
J 0
(3550 2075);
DISPLAY 0.872340 (3550 2075);
PAINT GREEN (3550 2075);
DISPLAY INVISIBLE (3550 2075);
FORCEPROP 1 LAST HDL_TAP TRUE
J 0
(3875 1900);
DISPLAY 0.872340 (3875 1900);
DISPLAY INVISIBLE (3875 1900);
FORCEPROP 1 LAST PATH I148
J 0
(3548 2025);
DISPLAY 0.872340 (3548 2025);
PAINT GREEN (3548 2025);
DISPLAY INVISIBLE (3548 2025);
FORCEADD TAP..1
(3550 2225);
FORCEPROP 3 LASTPIN (3500 2225) SIG_NAME M_G_CPU0_SB_DQS_DN<9>
J 0
(3510 2235);
DISPLAY 0.659574 (3510 2235);
PAINT MONO (3510 2235);
DISPLAY INVISIBLE (3510 2235);
FORCEPROP 1 LASTPIN (3500 2225) BN 9
J 0
(3488 2233);
DISPLAY 0.680851 (3488 2233);
PAINT GREEN (3488 2233);
FORCEPROP 2 LAST CDS_LIB standard
J 0
(3550 2225);
DISPLAY INVISIBLE (3550 2225);
FORCEPROP 1 LAST BODY_TYPE PLUMBING
J 0
(3550 2275);
DISPLAY 0.872340 (3550 2275);
PAINT GREEN (3550 2275);
DISPLAY INVISIBLE (3550 2275);
FORCEPROP 1 LAST HDL_TAP TRUE
J 0
(3875 2100);
DISPLAY 0.872340 (3875 2100);
DISPLAY INVISIBLE (3875 2100);
FORCEPROP 1 LAST PATH I149
J 0
(3548 2225);
DISPLAY 0.872340 (3548 2225);
PAINT GREEN (3548 2225);
DISPLAY INVISIBLE (3548 2225);
FORCEADD OFFPAGE..1
(-1975 2225);
FORCEPROP 2 LAST $XR0 26 
J 0
(-2196 2225);
DISPLAY 0.638298 (-2196 2225);
PAINT MONO (-2196 2225);
FORCEPROP 2 LAST CDS_LIB standard
J 0
(-1975 2225);
PAINT MONO (-1975 2225);
DISPLAY INVISIBLE (-1975 2225);
FORCEPROP 1 LAST OFFPAGE TRUE
J 0
(-1650 2100);
DISPLAY 0.872340 (-1650 2100);
DISPLAY INVISIBLE (-1650 2100);
FORCEPROP 1 LAST COMMENT_BODY TRUE
J 0
(-1850 2125);
DISPLAY 0.872340 (-1850 2125);
PAINT GREEN (-1850 2125);
DISPLAY INVISIBLE (-1850 2125);
FORCEPROP 2 LAST PATH I15
J 0
(-1925 2300);
DISPLAY 1.021277 (-1925 2300);
DISPLAY INVISIBLE (-1925 2300);
FORCEADD TAP..1
(3550 2125);
FORCEPROP 3 LASTPIN (3500 2125) SIG_NAME M_G_CPU0_SB_DQS_DN<8>
J 0
(3510 2135);
DISPLAY 0.659574 (3510 2135);
PAINT MONO (3510 2135);
DISPLAY INVISIBLE (3510 2135);
FORCEPROP 1 LASTPIN (3500 2125) BN 8
J 0
(3488 2133);
DISPLAY 0.680851 (3488 2133);
PAINT GREEN (3488 2133);
FORCEPROP 2 LAST CDS_LIB standard
J 0
(3550 2125);
DISPLAY INVISIBLE (3550 2125);
FORCEPROP 1 LAST BODY_TYPE PLUMBING
J 0
(3550 2175);
DISPLAY 0.872340 (3550 2175);
PAINT GREEN (3550 2175);
DISPLAY INVISIBLE (3550 2175);
FORCEPROP 1 LAST HDL_TAP TRUE
J 0
(3875 2000);
DISPLAY 0.872340 (3875 2000);
DISPLAY INVISIBLE (3875 2000);
FORCEPROP 1 LAST PATH I150
J 0
(3548 2125);
DISPLAY 0.872340 (3548 2125);
PAINT GREEN (3548 2125);
DISPLAY INVISIBLE (3548 2125);
FORCEADD TAP..1
(3550 2375);
FORCEPROP 3 LASTPIN (3500 2375) SIG_NAME M_G_CPU0_SA_DQS_DN<0>
J 0
(3510 2385);
DISPLAY 0.659574 (3510 2385);
PAINT MONO (3510 2385);
DISPLAY INVISIBLE (3510 2385);
FORCEPROP 1 LASTPIN (3500 2375) BN 0
J 0
(3488 2383);
DISPLAY 0.680851 (3488 2383);
PAINT GREEN (3488 2383);
FORCEPROP 2 LAST CDS_LIB standard
J 0
(3550 2375);
PAINT MONO (3550 2375);
DISPLAY INVISIBLE (3550 2375);
FORCEPROP 1 LAST BODY_TYPE PLUMBING
J 0
(3550 2425);
DISPLAY 0.872340 (3550 2425);
PAINT GREEN (3550 2425);
DISPLAY INVISIBLE (3550 2425);
FORCEPROP 1 LAST HDL_TAP TRUE
J 0
(3875 2250);
DISPLAY 0.872340 (3875 2250);
DISPLAY INVISIBLE (3875 2250);
FORCEPROP 1 LAST PATH I151
J 0
(3548 2375);
DISPLAY 0.872340 (3548 2375);
PAINT GREEN (3548 2375);
DISPLAY INVISIBLE (3548 2375);
FORCEADD TAP..1
(3550 2475);
FORCEPROP 3 LASTPIN (3500 2475) SIG_NAME M_G_CPU0_SA_DQS_DN<1>
J 0
(3510 2485);
DISPLAY 0.659574 (3510 2485);
PAINT MONO (3510 2485);
DISPLAY INVISIBLE (3510 2485);
FORCEPROP 1 LASTPIN (3500 2475) BN 1
J 0
(3488 2483);
DISPLAY 0.680851 (3488 2483);
PAINT GREEN (3488 2483);
FORCEPROP 2 LAST CDS_LIB standard
J 0
(3550 2475);
DISPLAY INVISIBLE (3550 2475);
FORCEPROP 1 LAST BODY_TYPE PLUMBING
J 0
(3550 2525);
DISPLAY 0.872340 (3550 2525);
PAINT GREEN (3550 2525);
DISPLAY INVISIBLE (3550 2525);
FORCEPROP 1 LAST HDL_TAP TRUE
J 0
(3875 2350);
DISPLAY 0.872340 (3875 2350);
DISPLAY INVISIBLE (3875 2350);
FORCEPROP 1 LAST PATH I152
J 0
(3548 2475);
DISPLAY 0.872340 (3548 2475);
PAINT GREEN (3548 2475);
DISPLAY INVISIBLE (3548 2475);
FORCEADD TAP..1
(3375 2525);
FORCEPROP 3 LASTPIN (3325 2525) SIG_NAME M_G_CPU0_SA_DQS_DP<1>
J 0
(3335 2535);
DISPLAY 0.659574 (3335 2535);
PAINT MONO (3335 2535);
DISPLAY INVISIBLE (3335 2535);
FORCEPROP 1 LASTPIN (3325 2525) BN 1
J 0
(3313 2533);
DISPLAY 0.680851 (3313 2533);
PAINT GREEN (3313 2533);
FORCEPROP 2 LAST CDS_LIB standard
J 0
(3375 2525);
DISPLAY INVISIBLE (3375 2525);
FORCEPROP 1 LAST BODY_TYPE PLUMBING
J 0
(3375 2575);
DISPLAY 0.872340 (3375 2575);
PAINT GREEN (3375 2575);
DISPLAY INVISIBLE (3375 2575);
FORCEPROP 1 LAST HDL_TAP TRUE
J 0
(3700 2400);
DISPLAY 0.872340 (3700 2400);
DISPLAY INVISIBLE (3700 2400);
FORCEPROP 1 LAST PATH I153
J 0
(3373 2525);
DISPLAY 0.872340 (3373 2525);
PAINT GREEN (3373 2525);
DISPLAY INVISIBLE (3373 2525);
FORCEADD TAP..1
(3375 2725);
FORCEPROP 3 LASTPIN (3325 2725) SIG_NAME M_G_CPU0_SA_DQS_DP<3>
J 0
(3335 2735);
DISPLAY 0.659574 (3335 2735);
PAINT MONO (3335 2735);
DISPLAY INVISIBLE (3335 2735);
FORCEPROP 1 LASTPIN (3325 2725) BN 3
J 0
(3313 2733);
DISPLAY 0.680851 (3313 2733);
PAINT GREEN (3313 2733);
FORCEPROP 2 LAST CDS_LIB standard
J 0
(3375 2725);
PAINT MONO (3375 2725);
DISPLAY INVISIBLE (3375 2725);
FORCEPROP 1 LAST BODY_TYPE PLUMBING
J 0
(3375 2775);
DISPLAY 0.872340 (3375 2775);
PAINT GREEN (3375 2775);
DISPLAY INVISIBLE (3375 2775);
FORCEPROP 1 LAST HDL_TAP TRUE
J 0
(3700 2600);
DISPLAY 0.872340 (3700 2600);
DISPLAY INVISIBLE (3700 2600);
FORCEPROP 1 LAST PATH I154
J 0
(3373 2725);
DISPLAY 0.872340 (3373 2725);
PAINT GREEN (3373 2725);
DISPLAY INVISIBLE (3373 2725);
FORCEADD TAP..1
(3375 2625);
FORCEPROP 3 LASTPIN (3325 2625) SIG_NAME M_G_CPU0_SA_DQS_DP<2>
J 0
(3335 2635);
DISPLAY 0.659574 (3335 2635);
PAINT MONO (3335 2635);
DISPLAY INVISIBLE (3335 2635);
FORCEPROP 1 LASTPIN (3325 2625) BN 2
J 0
(3313 2633);
DISPLAY 0.680851 (3313 2633);
PAINT GREEN (3313 2633);
FORCEPROP 2 LAST CDS_LIB standard
J 0
(3375 2625);
DISPLAY INVISIBLE (3375 2625);
FORCEPROP 1 LAST BODY_TYPE PLUMBING
J 0
(3375 2675);
DISPLAY 0.872340 (3375 2675);
PAINT GREEN (3375 2675);
DISPLAY INVISIBLE (3375 2675);
FORCEPROP 1 LAST HDL_TAP TRUE
J 0
(3700 2500);
DISPLAY 0.872340 (3700 2500);
DISPLAY INVISIBLE (3700 2500);
FORCEPROP 1 LAST PATH I155
J 0
(3373 2625);
DISPLAY 0.872340 (3373 2625);
PAINT GREEN (3373 2625);
DISPLAY INVISIBLE (3373 2625);
FORCEADD TAP..1
(3375 2825);
FORCEPROP 3 LASTPIN (3325 2825) SIG_NAME M_G_CPU0_SA_DQS_DP<4>
J 0
(3335 2835);
DISPLAY 0.659574 (3335 2835);
PAINT MONO (3335 2835);
DISPLAY INVISIBLE (3335 2835);
FORCEPROP 1 LASTPIN (3325 2825) BN 4
J 0
(3313 2833);
DISPLAY 0.680851 (3313 2833);
PAINT GREEN (3313 2833);
FORCEPROP 2 LAST CDS_LIB standard
J 0
(3375 2825);
PAINT MONO (3375 2825);
DISPLAY INVISIBLE (3375 2825);
FORCEPROP 1 LAST BODY_TYPE PLUMBING
J 0
(3375 2875);
DISPLAY 0.872340 (3375 2875);
PAINT GREEN (3375 2875);
DISPLAY INVISIBLE (3375 2875);
FORCEPROP 1 LAST HDL_TAP TRUE
J 0
(3700 2700);
DISPLAY 0.872340 (3700 2700);
DISPLAY INVISIBLE (3700 2700);
FORCEPROP 1 LAST PATH I156
J 0
(3373 2825);
DISPLAY 0.872340 (3373 2825);
PAINT GREEN (3373 2825);
DISPLAY INVISIBLE (3373 2825);
FORCEADD TAP..1
(3375 2925);
FORCEPROP 3 LASTPIN (3325 2925) SIG_NAME M_G_CPU0_SA_DQS_DP<5>
J 0
(3335 2935);
DISPLAY 0.659574 (3335 2935);
PAINT MONO (3335 2935);
DISPLAY INVISIBLE (3335 2935);
FORCEPROP 1 LASTPIN (3325 2925) BN 5
J 0
(3313 2933);
DISPLAY 0.680851 (3313 2933);
PAINT GREEN (3313 2933);
FORCEPROP 2 LAST CDS_LIB standard
J 0
(3375 2925);
DISPLAY INVISIBLE (3375 2925);
FORCEPROP 1 LAST BODY_TYPE PLUMBING
J 0
(3375 2975);
DISPLAY 0.872340 (3375 2975);
PAINT GREEN (3375 2975);
DISPLAY INVISIBLE (3375 2975);
FORCEPROP 1 LAST HDL_TAP TRUE
J 0
(3700 2800);
DISPLAY 0.872340 (3700 2800);
DISPLAY INVISIBLE (3700 2800);
FORCEPROP 1 LAST PATH I157
J 0
(3373 2925);
DISPLAY 0.872340 (3373 2925);
PAINT GREEN (3373 2925);
DISPLAY INVISIBLE (3373 2925);
FORCEADD TAP..1
(3550 2575);
FORCEPROP 3 LASTPIN (3500 2575) SIG_NAME M_G_CPU0_SA_DQS_DN<2>
J 0
(3510 2585);
DISPLAY 0.659574 (3510 2585);
PAINT MONO (3510 2585);
DISPLAY INVISIBLE (3510 2585);
FORCEPROP 1 LASTPIN (3500 2575) BN 2
J 0
(3488 2583);
DISPLAY 0.680851 (3488 2583);
PAINT GREEN (3488 2583);
FORCEPROP 2 LAST CDS_LIB standard
J 0
(3550 2575);
DISPLAY INVISIBLE (3550 2575);
FORCEPROP 1 LAST BODY_TYPE PLUMBING
J 0
(3550 2625);
DISPLAY 0.872340 (3550 2625);
PAINT GREEN (3550 2625);
DISPLAY INVISIBLE (3550 2625);
FORCEPROP 1 LAST HDL_TAP TRUE
J 0
(3875 2450);
DISPLAY 0.872340 (3875 2450);
DISPLAY INVISIBLE (3875 2450);
FORCEPROP 1 LAST PATH I158
J 0
(3548 2575);
DISPLAY 0.872340 (3548 2575);
PAINT GREEN (3548 2575);
DISPLAY INVISIBLE (3548 2575);
FORCEADD TAP..1
(3550 2675);
FORCEPROP 3 LASTPIN (3500 2675) SIG_NAME M_G_CPU0_SA_DQS_DN<3>
J 0
(3510 2685);
DISPLAY 0.659574 (3510 2685);
PAINT MONO (3510 2685);
DISPLAY INVISIBLE (3510 2685);
FORCEPROP 1 LASTPIN (3500 2675) BN 3
J 0
(3488 2683);
DISPLAY 0.680851 (3488 2683);
PAINT GREEN (3488 2683);
FORCEPROP 2 LAST CDS_LIB standard
J 0
(3550 2675);
PAINT MONO (3550 2675);
DISPLAY INVISIBLE (3550 2675);
FORCEPROP 1 LAST BODY_TYPE PLUMBING
J 0
(3550 2725);
DISPLAY 0.872340 (3550 2725);
PAINT GREEN (3550 2725);
DISPLAY INVISIBLE (3550 2725);
FORCEPROP 1 LAST HDL_TAP TRUE
J 0
(3875 2550);
DISPLAY 0.872340 (3875 2550);
DISPLAY INVISIBLE (3875 2550);
FORCEPROP 1 LAST PATH I159
J 0
(3548 2675);
DISPLAY 0.872340 (3548 2675);
PAINT GREEN (3548 2675);
DISPLAY INVISIBLE (3548 2675);
FORCEADD OFFPAGE..1
(-1975 2325);
FORCEPROP 2 LAST $XR0 26 
J 0
(-2196 2325);
DISPLAY 0.638298 (-2196 2325);
PAINT MONO (-2196 2325);
FORCEPROP 2 LAST CDS_LIB standard
J 0
(-1975 2325);
PAINT MONO (-1975 2325);
DISPLAY INVISIBLE (-1975 2325);
FORCEPROP 1 LAST OFFPAGE TRUE
J 0
(-1650 2200);
DISPLAY 0.872340 (-1650 2200);
DISPLAY INVISIBLE (-1650 2200);
FORCEPROP 1 LAST COMMENT_BODY TRUE
J 0
(-1850 2225);
DISPLAY 0.872340 (-1850 2225);
PAINT GREEN (-1850 2225);
DISPLAY INVISIBLE (-1850 2225);
FORCEPROP 2 LAST PATH I16
J 0
(-1925 2400);
DISPLAY 1.021277 (-1925 2400);
DISPLAY INVISIBLE (-1925 2400);
FORCEADD TAP..1
(3550 2775);
FORCEPROP 3 LASTPIN (3500 2775) SIG_NAME M_G_CPU0_SA_DQS_DN<4>
J 0
(3510 2785);
DISPLAY 0.659574 (3510 2785);
PAINT MONO (3510 2785);
DISPLAY INVISIBLE (3510 2785);
FORCEPROP 1 LASTPIN (3500 2775) BN 4
J 0
(3488 2783);
DISPLAY 0.680851 (3488 2783);
PAINT GREEN (3488 2783);
FORCEPROP 2 LAST CDS_LIB standard
J 0
(3550 2775);
PAINT MONO (3550 2775);
DISPLAY INVISIBLE (3550 2775);
FORCEPROP 1 LAST BODY_TYPE PLUMBING
J 0
(3550 2825);
DISPLAY 0.872340 (3550 2825);
PAINT GREEN (3550 2825);
DISPLAY INVISIBLE (3550 2825);
FORCEPROP 1 LAST HDL_TAP TRUE
J 0
(3875 2650);
DISPLAY 0.872340 (3875 2650);
DISPLAY INVISIBLE (3875 2650);
FORCEPROP 1 LAST PATH I160
J 0
(3548 2775);
DISPLAY 0.872340 (3548 2775);
PAINT GREEN (3548 2775);
DISPLAY INVISIBLE (3548 2775);
FORCEADD TAP..1
(3550 2975);
FORCEPROP 3 LASTPIN (3500 2975) SIG_NAME M_G_CPU0_SA_DQS_DN<6>
J 0
(3510 2985);
DISPLAY 0.659574 (3510 2985);
PAINT MONO (3510 2985);
DISPLAY INVISIBLE (3510 2985);
FORCEPROP 1 LASTPIN (3500 2975) BN 6
J 0
(3488 2983);
DISPLAY 0.680851 (3488 2983);
PAINT GREEN (3488 2983);
FORCEPROP 2 LAST CDS_LIB standard
J 0
(3550 2975);
DISPLAY INVISIBLE (3550 2975);
FORCEPROP 1 LAST BODY_TYPE PLUMBING
J 0
(3550 3025);
DISPLAY 0.872340 (3550 3025);
PAINT GREEN (3550 3025);
DISPLAY INVISIBLE (3550 3025);
FORCEPROP 1 LAST HDL_TAP TRUE
J 0
(3875 2850);
DISPLAY 0.872340 (3875 2850);
DISPLAY INVISIBLE (3875 2850);
FORCEPROP 1 LAST PATH I161
J 0
(3548 2975);
DISPLAY 0.872340 (3548 2975);
PAINT GREEN (3548 2975);
DISPLAY INVISIBLE (3548 2975);
FORCEADD TAP..1
(3550 2875);
FORCEPROP 3 LASTPIN (3500 2875) SIG_NAME M_G_CPU0_SA_DQS_DN<5>
J 0
(3510 2885);
DISPLAY 0.659574 (3510 2885);
PAINT MONO (3510 2885);
DISPLAY INVISIBLE (3510 2885);
FORCEPROP 1 LASTPIN (3500 2875) BN 5
J 0
(3488 2883);
DISPLAY 0.680851 (3488 2883);
PAINT GREEN (3488 2883);
FORCEPROP 2 LAST CDS_LIB standard
J 0
(3550 2875);
DISPLAY INVISIBLE (3550 2875);
FORCEPROP 1 LAST BODY_TYPE PLUMBING
J 0
(3550 2925);
DISPLAY 0.872340 (3550 2925);
PAINT GREEN (3550 2925);
DISPLAY INVISIBLE (3550 2925);
FORCEPROP 1 LAST HDL_TAP TRUE
J 0
(3875 2750);
DISPLAY 0.872340 (3875 2750);
DISPLAY INVISIBLE (3875 2750);
FORCEPROP 1 LAST PATH I162
J 0
(3548 2875);
DISPLAY 0.872340 (3548 2875);
PAINT GREEN (3548 2875);
DISPLAY INVISIBLE (3548 2875);
FORCEADD OFFPAGE..2
(4500 2250);
FORCEPROP 2 LAST $XR1 94 
J 0
(4779 2250);
DISPLAY 0.638298 (4779 2250);
PAINT MONO (4779 2250);
FORCEPROP 2 LAST $XR0 26 
J 0
(4689 2250);
DISPLAY 0.638298 (4689 2250);
PAINT MONO (4689 2250);
FORCEPROP 2 LAST CDS_LIB standard
J 0
(4500 2250);
PAINT MONO (4500 2250);
DISPLAY INVISIBLE (4500 2250);
FORCEPROP 1 LAST OFFPAGE TRUE
J 0
(4825 2125);
DISPLAY 1.170213 (4825 2125);
PAINT GREEN (4825 2125);
DISPLAY INVISIBLE (4825 2125);
FORCEPROP 1 LAST COMMENT_BODY TRUE
J 0
(4455 2155);
DISPLAY 1.170213 (4455 2155);
PAINT GREEN (4455 2155);
DISPLAY INVISIBLE (4455 2155);
FORCEPROP 2 LAST PATH I163
J 0
(4675 2325);
DISPLAY 1.021277 (4675 2325);
DISPLAY INVISIBLE (4675 2325);
FORCEADD OFFPAGE..2
(4500 2300);
FORCEPROP 2 LAST $XR1 94 
J 0
(4779 2300);
DISPLAY 0.638298 (4779 2300);
PAINT MONO (4779 2300);
FORCEPROP 2 LAST $XR0 26 
J 0
(4689 2300);
DISPLAY 0.638298 (4689 2300);
PAINT MONO (4689 2300);
FORCEPROP 2 LAST CDS_LIB standard
J 0
(4500 2300);
PAINT MONO (4500 2300);
DISPLAY INVISIBLE (4500 2300);
FORCEPROP 1 LAST OFFPAGE TRUE
J 0
(4825 2175);
DISPLAY 1.170213 (4825 2175);
PAINT GREEN (4825 2175);
DISPLAY INVISIBLE (4825 2175);
FORCEPROP 1 LAST COMMENT_BODY TRUE
J 0
(4455 2205);
DISPLAY 1.170213 (4455 2205);
PAINT GREEN (4455 2205);
DISPLAY INVISIBLE (4455 2205);
FORCEPROP 2 LAST PATH I164
J 0
(4675 2375);
DISPLAY 1.021277 (4675 2375);
DISPLAY INVISIBLE (4675 2375);
FORCEADD OFFPAGE..3
(1425 3350);
FORCEPROP 2 LAST $XR1 94 
J 0
(1729 3350);
DISPLAY 0.638298 (1729 3350);
PAINT MONO (1729 3350);
FORCEPROP 2 LAST $XR0 26 
J 0
(1639 3350);
DISPLAY 0.638298 (1639 3350);
PAINT MONO (1639 3350);
FORCEPROP 2 LAST CDS_LIB standard
J 2
(1425 3350);
DISPLAY INVISIBLE (1425 3350);
FORCEPROP 1 LAST OFFPAGE TRUE
J 0
(1750 3225);
DISPLAY 0.872340 (1750 3225);
DISPLAY INVISIBLE (1750 3225);
FORCEPROP 1 LAST COMMENT_BODY TRUE
J 0
(1375 3250);
DISPLAY 0.872340 (1375 3250);
PAINT GREEN (1375 3250);
DISPLAY INVISIBLE (1375 3250);
FORCEPROP 2 LAST PATH I165
J 0
(1625 3425);
DISPLAY 1.021277 (1625 3425);
DISPLAY INVISIBLE (1625 3425);
FORCEADD TAP..1
(3375 3025);
FORCEPROP 3 LASTPIN (3325 3025) SIG_NAME M_G_CPU0_SA_DQS_DP<6>
J 0
(3335 3035);
DISPLAY 0.659574 (3335 3035);
PAINT MONO (3335 3035);
DISPLAY INVISIBLE (3335 3035);
FORCEPROP 1 LASTPIN (3325 3025) BN 6
J 0
(3313 3033);
DISPLAY 0.680851 (3313 3033);
PAINT GREEN (3313 3033);
FORCEPROP 2 LAST CDS_LIB standard
J 0
(3375 3025);
DISPLAY INVISIBLE (3375 3025);
FORCEPROP 1 LAST BODY_TYPE PLUMBING
J 0
(3375 3075);
DISPLAY 0.872340 (3375 3075);
PAINT GREEN (3375 3075);
DISPLAY INVISIBLE (3375 3075);
FORCEPROP 1 LAST HDL_TAP TRUE
J 0
(3700 2900);
DISPLAY 0.872340 (3700 2900);
DISPLAY INVISIBLE (3700 2900);
FORCEPROP 1 LAST PATH I166
J 0
(3373 3025);
DISPLAY 0.872340 (3373 3025);
PAINT GREEN (3373 3025);
DISPLAY INVISIBLE (3373 3025);
FORCEADD TAP..1
(3375 3225);
FORCEPROP 3 LASTPIN (3325 3225) SIG_NAME M_G_CPU0_SA_DQS_DP<8>
J 0
(3335 3235);
DISPLAY 0.659574 (3335 3235);
PAINT MONO (3335 3235);
DISPLAY INVISIBLE (3335 3235);
FORCEPROP 1 LASTPIN (3325 3225) BN 8
J 0
(3313 3233);
DISPLAY 0.680851 (3313 3233);
PAINT GREEN (3313 3233);
FORCEPROP 2 LAST CDS_LIB standard
J 0
(3375 3225);
DISPLAY INVISIBLE (3375 3225);
FORCEPROP 1 LAST BODY_TYPE PLUMBING
J 0
(3375 3275);
DISPLAY 0.872340 (3375 3275);
PAINT GREEN (3375 3275);
DISPLAY INVISIBLE (3375 3275);
FORCEPROP 1 LAST HDL_TAP TRUE
J 0
(3700 3100);
DISPLAY 0.872340 (3700 3100);
DISPLAY INVISIBLE (3700 3100);
FORCEPROP 1 LAST PATH I167
J 0
(3373 3225);
DISPLAY 0.872340 (3373 3225);
PAINT GREEN (3373 3225);
DISPLAY INVISIBLE (3373 3225);
FORCEADD TAP..1
(3375 3125);
FORCEPROP 3 LASTPIN (3325 3125) SIG_NAME M_G_CPU0_SA_DQS_DP<7>
J 0
(3335 3135);
DISPLAY 0.659574 (3335 3135);
PAINT MONO (3335 3135);
DISPLAY INVISIBLE (3335 3135);
FORCEPROP 1 LASTPIN (3325 3125) BN 7
J 0
(3313 3133);
DISPLAY 0.680851 (3313 3133);
PAINT GREEN (3313 3133);
FORCEPROP 2 LAST CDS_LIB standard
J 0
(3375 3125);
DISPLAY INVISIBLE (3375 3125);
FORCEPROP 1 LAST BODY_TYPE PLUMBING
J 0
(3375 3175);
DISPLAY 0.872340 (3375 3175);
PAINT GREEN (3375 3175);
DISPLAY INVISIBLE (3375 3175);
FORCEPROP 1 LAST HDL_TAP TRUE
J 0
(3700 3000);
DISPLAY 0.872340 (3700 3000);
DISPLAY INVISIBLE (3700 3000);
FORCEPROP 1 LAST PATH I168
J 0
(3373 3125);
DISPLAY 0.872340 (3373 3125);
PAINT GREEN (3373 3125);
DISPLAY INVISIBLE (3373 3125);
FORCEADD TAP..1
(3375 3325);
FORCEPROP 3 LASTPIN (3325 3325) SIG_NAME M_G_CPU0_SA_DQS_DP<9>
J 0
(3335 3335);
DISPLAY 0.659574 (3335 3335);
PAINT MONO (3335 3335);
DISPLAY INVISIBLE (3335 3335);
FORCEPROP 1 LASTPIN (3325 3325) BN 9
J 0
(3313 3333);
DISPLAY 0.680851 (3313 3333);
PAINT GREEN (3313 3333);
FORCEPROP 2 LAST CDS_LIB standard
J 0
(3375 3325);
DISPLAY INVISIBLE (3375 3325);
FORCEPROP 1 LAST BODY_TYPE PLUMBING
J 0
(3375 3375);
DISPLAY 0.872340 (3375 3375);
PAINT GREEN (3375 3375);
DISPLAY INVISIBLE (3375 3375);
FORCEPROP 1 LAST HDL_TAP TRUE
J 0
(3700 3200);
DISPLAY 0.872340 (3700 3200);
DISPLAY INVISIBLE (3700 3200);
FORCEPROP 1 LAST PATH I169
J 0
(3373 3325);
DISPLAY 0.872340 (3373 3325);
PAINT GREEN (3373 3325);
DISPLAY INVISIBLE (3373 3325);
FORCEADD OFFPAGE..1
(-1975 2375);
FORCEPROP 2 LAST $XR0 26 
J 0
(-2196 2375);
DISPLAY 0.638298 (-2196 2375);
PAINT MONO (-2196 2375);
FORCEPROP 2 LAST CDS_LIB standard
J 0
(-1975 2375);
PAINT MONO (-1975 2375);
DISPLAY INVISIBLE (-1975 2375);
FORCEPROP 1 LAST OFFPAGE TRUE
J 0
(-1650 2250);
DISPLAY 0.872340 (-1650 2250);
DISPLAY INVISIBLE (-1650 2250);
FORCEPROP 1 LAST COMMENT_BODY TRUE
J 0
(-1850 2275);
DISPLAY 0.872340 (-1850 2275);
PAINT GREEN (-1850 2275);
DISPLAY INVISIBLE (-1850 2275);
FORCEPROP 2 LAST PATH I17
J 0
(-1925 2450);
DISPLAY 1.021277 (-1925 2450);
DISPLAY INVISIBLE (-1925 2450);
FORCEADD TAP..1
(3550 3075);
FORCEPROP 3 LASTPIN (3500 3075) SIG_NAME M_G_CPU0_SA_DQS_DN<7>
J 0
(3510 3085);
DISPLAY 0.659574 (3510 3085);
PAINT MONO (3510 3085);
DISPLAY INVISIBLE (3510 3085);
FORCEPROP 1 LASTPIN (3500 3075) BN 7
J 0
(3488 3083);
DISPLAY 0.680851 (3488 3083);
PAINT GREEN (3488 3083);
FORCEPROP 2 LAST CDS_LIB standard
J 0
(3550 3075);
DISPLAY INVISIBLE (3550 3075);
FORCEPROP 1 LAST BODY_TYPE PLUMBING
J 0
(3550 3125);
DISPLAY 0.872340 (3550 3125);
PAINT GREEN (3550 3125);
DISPLAY INVISIBLE (3550 3125);
FORCEPROP 1 LAST HDL_TAP TRUE
J 0
(3875 2950);
DISPLAY 0.872340 (3875 2950);
DISPLAY INVISIBLE (3875 2950);
FORCEPROP 1 LAST PATH I170
J 0
(3548 3075);
DISPLAY 0.872340 (3548 3075);
PAINT GREEN (3548 3075);
DISPLAY INVISIBLE (3548 3075);
FORCEADD TAP..1
(3550 3175);
FORCEPROP 3 LASTPIN (3500 3175) SIG_NAME M_G_CPU0_SA_DQS_DN<8>
J 0
(3510 3185);
DISPLAY 0.659574 (3510 3185);
PAINT MONO (3510 3185);
DISPLAY INVISIBLE (3510 3185);
FORCEPROP 1 LASTPIN (3500 3175) BN 8
J 0
(3488 3183);
DISPLAY 0.680851 (3488 3183);
PAINT GREEN (3488 3183);
FORCEPROP 2 LAST CDS_LIB standard
J 0
(3550 3175);
DISPLAY INVISIBLE (3550 3175);
FORCEPROP 1 LAST BODY_TYPE PLUMBING
J 0
(3550 3225);
DISPLAY 0.872340 (3550 3225);
PAINT GREEN (3550 3225);
DISPLAY INVISIBLE (3550 3225);
FORCEPROP 1 LAST HDL_TAP TRUE
J 0
(3875 3050);
DISPLAY 0.872340 (3875 3050);
DISPLAY INVISIBLE (3875 3050);
FORCEPROP 1 LAST PATH I171
J 0
(3548 3175);
DISPLAY 0.872340 (3548 3175);
PAINT GREEN (3548 3175);
DISPLAY INVISIBLE (3548 3175);
FORCEADD TAP..1
(3550 3275);
FORCEPROP 3 LASTPIN (3500 3275) SIG_NAME M_G_CPU0_SA_DQS_DN<9>
J 0
(3510 3285);
DISPLAY 0.659574 (3510 3285);
PAINT MONO (3510 3285);
DISPLAY INVISIBLE (3510 3285);
FORCEPROP 1 LASTPIN (3500 3275) BN 9
J 0
(3488 3283);
DISPLAY 0.680851 (3488 3283);
PAINT GREEN (3488 3283);
FORCEPROP 2 LAST CDS_LIB standard
J 0
(3550 3275);
DISPLAY INVISIBLE (3550 3275);
FORCEPROP 1 LAST BODY_TYPE PLUMBING
J 0
(3550 3325);
DISPLAY 0.872340 (3550 3325);
PAINT GREEN (3550 3325);
DISPLAY INVISIBLE (3550 3325);
FORCEPROP 1 LAST HDL_TAP TRUE
J 0
(3875 3150);
DISPLAY 0.872340 (3875 3150);
DISPLAY INVISIBLE (3875 3150);
FORCEPROP 1 LAST PATH I172
J 0
(3548 3275);
DISPLAY 0.872340 (3548 3275);
PAINT GREEN (3548 3275);
DISPLAY INVISIBLE (3548 3275);
FORCEADD OFFPAGE..2
(4500 3350);
FORCEPROP 2 LAST $XR1 94 
J 0
(4779 3350);
DISPLAY 0.638298 (4779 3350);
PAINT MONO (4779 3350);
FORCEPROP 2 LAST $XR0 26 
J 0
(4689 3350);
DISPLAY 0.638298 (4689 3350);
PAINT MONO (4689 3350);
FORCEPROP 2 LAST CDS_LIB standard
J 0
(4500 3350);
PAINT MONO (4500 3350);
DISPLAY INVISIBLE (4500 3350);
FORCEPROP 1 LAST OFFPAGE TRUE
J 0
(4825 3225);
DISPLAY 1.170213 (4825 3225);
PAINT GREEN (4825 3225);
DISPLAY INVISIBLE (4825 3225);
FORCEPROP 1 LAST COMMENT_BODY TRUE
J 0
(4455 3255);
DISPLAY 1.170213 (4455 3255);
PAINT GREEN (4455 3255);
DISPLAY INVISIBLE (4455 3255);
FORCEPROP 2 LAST PATH I173
J 0
(4675 3425);
DISPLAY 1.021277 (4675 3425);
DISPLAY INVISIBLE (4675 3425);
FORCEADD OFFPAGE..2
(4500 3300);
FORCEPROP 2 LAST $XR1 94 
J 0
(4779 3300);
DISPLAY 0.638298 (4779 3300);
PAINT MONO (4779 3300);
FORCEPROP 2 LAST $XR0 26 
J 0
(4689 3300);
DISPLAY 0.638298 (4689 3300);
PAINT MONO (4689 3300);
FORCEPROP 2 LAST CDS_LIB standard
J 0
(4500 3300);
PAINT MONO (4500 3300);
DISPLAY INVISIBLE (4500 3300);
FORCEPROP 1 LAST OFFPAGE TRUE
J 0
(4825 3175);
DISPLAY 1.170213 (4825 3175);
PAINT GREEN (4825 3175);
DISPLAY INVISIBLE (4825 3175);
FORCEPROP 1 LAST COMMENT_BODY TRUE
J 0
(4455 3205);
DISPLAY 1.170213 (4455 3205);
PAINT GREEN (4455 3205);
DISPLAY INVISIBLE (4455 3205);
FORCEPROP 2 LAST PATH I174
J 0
(4675 3375);
DISPLAY 1.021277 (4675 3375);
DISPLAY INVISIBLE (4675 3375);
FORCEADD VCC_CORE..1
(5025 3875);
FORCEPROP 3 LASTPIN (5025 3825) SIG_NAME P12V_S3_AUX_CPU0_NVDIMM\g
J 0
(5035 3835);
DISPLAY 0.659574 (5035 3835);
PAINT MONO (5035 3835);
DISPLAY INVISIBLE (5035 3835);
FORCEPROP 1 LAST HDL_POWER P12V_S3_AUX_CPU0_NVDIMM
J 1
(5025 3925);
DISPLAY 1.148936 (5025 3925);
PAINT GREEN (5025 3925);
FORCEPROP 2 LAST CDS_LIB logical_power
J 0
(5025 3875);
PAINT MONO (5025 3875);
DISPLAY INVISIBLE (5025 3875);
FORCEPROP 1 LAST PATH I175
J 0
(5075 3900);
DISPLAY 0.872340 (5075 3900);
PAINT AQUA (5075 3900);
DISPLAY INVISIBLE (5075 3900);
FORCEADD SCONN288_ADR50017P087CC..3
(5875 1700);
FORCEPROP 1 LAST PART_NUMBER DFHST8FS460
J 0
(5420 3624);
DISPLAY 0.723404 (5420 3624);
PAINT GREEN (5420 3624);
DISPLAY INVISIBLE (5420 3624);
FORCEPROP 2 LAST PART_TYPE SMLF
J 0
(5425 3775);
DISPLAY 1.021277 (5425 3775);
FORCEPROP 2 LAST VALUE SCONN288_ADR50017-P087CC
J 0
(5425 3725);
DISPLAY 1.021277 (5425 3725);
FORCEPROP 1 LAST MATERIAL IO
J 0
(5420 3497);
DISPLAY 0.723404 (5420 3497);
PAINT GREEN (5420 3497);
FORCEPROP 1 LAST $LOCATION J14
J 0
(5425 3675);
DISPLAY 0.723404 (5425 3675);
PAINT GREEN (5425 3675);
FORCEPROP 0 LASTPIN (6475 75) $PN G1
J 0
(6485 85);
DISPLAY 0.680851 (6485 85);
PAINT MONO (6485 85);
FORCEPROP 0 LASTPIN (6475 25) $PN G2
J 0
(6485 35);
DISPLAY 0.680851 (6485 35);
PAINT MONO (6485 35);
FORCEPROP 0 LASTPIN (6475 -25) $PN G3
J 0
(6485 -15);
DISPLAY 0.680851 (6485 -15);
PAINT MONO (6485 -15);
FORCEPROP 0 LASTPIN (5275 3225) $PN 1
J 2
(5265 3235);
DISPLAY 0.680851 (5265 3235);
PAINT MONO (5265 3235);
FORCEPROP 0 LASTPIN (5275 3275) $PN 145
J 2
(5265 3285);
DISPLAY 0.680851 (5265 3285);
PAINT MONO (5265 3285);
FORCEPROP 0 LASTPIN (5275 3325) $PN 146
J 2
(5265 3335);
DISPLAY 0.680851 (5265 3335);
PAINT MONO (5265 3335);
FORCEPROP 0 LASTPIN (6475 175) $PN 6
J 0
(6485 185);
DISPLAY 0.680851 (6485 185);
PAINT MONO (6485 185);
FORCEPROP 0 LASTPIN (6475 225) $PN 8
J 0
(6485 235);
DISPLAY 0.680851 (6485 235);
PAINT MONO (6485 235);
FORCEPROP 0 LASTPIN (6475 275) $PN 10
J 0
(6485 285);
DISPLAY 0.680851 (6485 285);
PAINT MONO (6485 285);
FORCEPROP 0 LASTPIN (6475 325) $PN 13
J 0
(6485 335);
DISPLAY 0.680851 (6485 335);
PAINT MONO (6485 335);
FORCEPROP 0 LASTPIN (6475 375) $PN 15
J 0
(6485 385);
DISPLAY 0.680851 (6485 385);
PAINT MONO (6485 385);
FORCEPROP 0 LASTPIN (6475 425) $PN 17
J 0
(6485 435);
DISPLAY 0.680851 (6485 435);
PAINT MONO (6485 435);
FORCEPROP 0 LASTPIN (6475 475) $PN 19
J 0
(6485 485);
DISPLAY 0.680851 (6485 485);
PAINT MONO (6485 485);
FORCEPROP 0 LASTPIN (6475 525) $PN 21
J 0
(6485 535);
DISPLAY 0.680851 (6485 535);
PAINT MONO (6485 535);
FORCEPROP 0 LASTPIN (6475 575) $PN 24
J 0
(6485 585);
DISPLAY 0.680851 (6485 585);
PAINT MONO (6485 585);
FORCEPROP 0 LASTPIN (6475 625) $PN 26
J 0
(6485 635);
DISPLAY 0.680851 (6485 635);
PAINT MONO (6485 635);
FORCEPROP 0 LASTPIN (6475 675) $PN 28
J 0
(6485 685);
DISPLAY 0.680851 (6485 685);
PAINT MONO (6485 685);
FORCEPROP 0 LASTPIN (6475 725) $PN 30
J 0
(6485 735);
DISPLAY 0.680851 (6485 735);
PAINT MONO (6485 735);
FORCEPROP 0 LASTPIN (6475 775) $PN 32
J 0
(6485 785);
DISPLAY 0.680851 (6485 785);
PAINT MONO (6485 785);
FORCEPROP 0 LASTPIN (6475 825) $PN 35
J 0
(6485 835);
DISPLAY 0.680851 (6485 835);
PAINT MONO (6485 835);
FORCEPROP 0 LASTPIN (6475 875) $PN 37
J 0
(6485 885);
DISPLAY 0.680851 (6485 885);
PAINT MONO (6485 885);
FORCEPROP 0 LASTPIN (6475 925) $PN 39
J 0
(6485 935);
DISPLAY 0.680851 (6485 935);
PAINT MONO (6485 935);
FORCEPROP 0 LASTPIN (6475 975) $PN 41
J 0
(6485 985);
DISPLAY 0.680851 (6485 985);
PAINT MONO (6485 985);
FORCEPROP 0 LASTPIN (6475 1025) $PN 43
J 0
(6485 1035);
DISPLAY 0.680851 (6485 1035);
PAINT MONO (6485 1035);
FORCEPROP 0 LASTPIN (6475 1075) $PN 46
J 0
(6485 1085);
DISPLAY 0.680851 (6485 1085);
PAINT MONO (6485 1085);
FORCEPROP 0 LASTPIN (6475 1125) $PN 48
J 0
(6485 1135);
DISPLAY 0.680851 (6485 1135);
PAINT MONO (6485 1135);
FORCEPROP 0 LASTPIN (6475 1175) $PN 50
J 0
(6485 1185);
DISPLAY 0.680851 (6485 1185);
PAINT MONO (6485 1185);
FORCEPROP 0 LASTPIN (6475 1225) $PN 52
J 0
(6485 1235);
DISPLAY 0.680851 (6485 1235);
PAINT MONO (6485 1235);
FORCEPROP 0 LASTPIN (6475 1275) $PN 54
J 0
(6485 1285);
DISPLAY 0.680851 (6485 1285);
PAINT MONO (6485 1285);
FORCEPROP 0 LASTPIN (6475 1325) $PN 57
J 0
(6485 1335);
DISPLAY 0.680851 (6485 1335);
PAINT MONO (6485 1335);
FORCEPROP 0 LASTPIN (6475 1375) $PN 59
J 0
(6485 1385);
DISPLAY 0.680851 (6485 1385);
PAINT MONO (6485 1385);
FORCEPROP 0 LASTPIN (6475 1425) $PN 61
J 0
(6485 1435);
DISPLAY 0.680851 (6485 1435);
PAINT MONO (6485 1435);
FORCEPROP 0 LASTPIN (6475 1475) $PN 63
J 0
(6485 1485);
DISPLAY 0.680851 (6485 1485);
PAINT MONO (6485 1485);
FORCEPROP 0 LASTPIN (6475 1525) $PN 65
J 0
(6485 1535);
DISPLAY 0.680851 (6485 1535);
PAINT MONO (6485 1535);
FORCEPROP 0 LASTPIN (6475 1575) $PN 67
J 0
(6485 1585);
DISPLAY 0.680851 (6485 1585);
PAINT MONO (6485 1585);
FORCEPROP 0 LASTPIN (6475 1625) $PN 69
J 0
(6485 1635);
DISPLAY 0.680851 (6485 1635);
PAINT MONO (6485 1635);
FORCEPROP 0 LASTPIN (6475 1675) $PN 71
J 0
(6485 1685);
DISPLAY 0.680851 (6485 1685);
PAINT MONO (6485 1685);
FORCEPROP 0 LASTPIN (6475 1725) $PN 73
J 0
(6485 1735);
DISPLAY 0.680851 (6485 1735);
PAINT MONO (6485 1735);
FORCEPROP 0 LASTPIN (6475 1775) $PN 75
J 0
(6485 1785);
DISPLAY 0.680851 (6485 1785);
PAINT MONO (6485 1785);
FORCEPROP 0 LASTPIN (6475 1825) $PN 77
J 0
(6485 1835);
DISPLAY 0.680851 (6485 1835);
PAINT MONO (6485 1835);
FORCEPROP 0 LASTPIN (6475 1875) $PN 79
J 0
(6485 1885);
DISPLAY 0.680851 (6485 1885);
PAINT MONO (6485 1885);
FORCEPROP 0 LASTPIN (6475 1925) $PN 81
J 0
(6485 1935);
DISPLAY 0.680851 (6485 1935);
PAINT MONO (6485 1935);
FORCEPROP 0 LASTPIN (6475 1975) $PN 83
J 0
(6485 1985);
DISPLAY 0.680851 (6485 1985);
PAINT MONO (6485 1985);
FORCEPROP 0 LASTPIN (6475 2025) $PN 85
J 0
(6485 2035);
DISPLAY 0.680851 (6485 2035);
PAINT MONO (6485 2035);
FORCEPROP 0 LASTPIN (6475 2075) $PN 88
J 0
(6485 2085);
DISPLAY 0.680851 (6485 2085);
PAINT MONO (6485 2085);
FORCEPROP 0 LASTPIN (6475 2125) $PN 90
J 0
(6485 2135);
DISPLAY 0.680851 (6485 2135);
PAINT MONO (6485 2135);
FORCEPROP 0 LASTPIN (6475 2175) $PN 92
J 0
(6485 2185);
DISPLAY 0.680851 (6485 2185);
PAINT MONO (6485 2185);
FORCEPROP 0 LASTPIN (6475 2225) $PN 95
J 0
(6485 2235);
DISPLAY 0.680851 (6485 2235);
PAINT MONO (6485 2235);
FORCEPROP 0 LASTPIN (6475 2275) $PN 97
J 0
(6485 2285);
DISPLAY 0.680851 (6485 2285);
PAINT MONO (6485 2285);
FORCEPROP 0 LASTPIN (6475 2325) $PN 99
J 0
(6485 2335);
DISPLAY 0.680851 (6485 2335);
PAINT MONO (6485 2335);
FORCEPROP 0 LASTPIN (6475 2375) $PN 101
J 0
(6485 2385);
DISPLAY 0.680851 (6485 2385);
PAINT MONO (6485 2385);
FORCEPROP 0 LASTPIN (6475 2425) $PN 103
J 0
(6485 2435);
DISPLAY 0.680851 (6485 2435);
PAINT MONO (6485 2435);
FORCEPROP 0 LASTPIN (6475 2475) $PN 106
J 0
(6485 2485);
DISPLAY 0.680851 (6485 2485);
PAINT MONO (6485 2485);
FORCEPROP 0 LASTPIN (6475 2525) $PN 108
J 0
(6485 2535);
DISPLAY 0.680851 (6485 2535);
PAINT MONO (6485 2535);
FORCEPROP 0 LASTPIN (6475 2575) $PN 110
J 0
(6485 2585);
DISPLAY 0.680851 (6485 2585);
PAINT MONO (6485 2585);
FORCEPROP 0 LASTPIN (6475 2625) $PN 112
J 0
(6485 2635);
DISPLAY 0.680851 (6485 2635);
PAINT MONO (6485 2635);
FORCEPROP 0 LASTPIN (6475 2675) $PN 114
J 0
(6485 2685);
DISPLAY 0.680851 (6485 2685);
PAINT MONO (6485 2685);
FORCEPROP 0 LASTPIN (6475 2725) $PN 117
J 0
(6485 2735);
DISPLAY 0.680851 (6485 2735);
PAINT MONO (6485 2735);
FORCEPROP 0 LASTPIN (6475 2775) $PN 119
J 0
(6485 2785);
DISPLAY 0.680851 (6485 2785);
PAINT MONO (6485 2785);
FORCEPROP 0 LASTPIN (6475 2825) $PN 121
J 0
(6485 2835);
DISPLAY 0.680851 (6485 2835);
PAINT MONO (6485 2835);
FORCEPROP 0 LASTPIN (6475 2875) $PN 123
J 0
(6485 2885);
DISPLAY 0.680851 (6485 2885);
PAINT MONO (6485 2885);
FORCEPROP 0 LASTPIN (6475 2925) $PN 125
J 0
(6485 2935);
DISPLAY 0.680851 (6485 2935);
PAINT MONO (6485 2935);
FORCEPROP 0 LASTPIN (6475 2975) $PN 128
J 0
(6485 2985);
DISPLAY 0.680851 (6485 2985);
PAINT MONO (6485 2985);
FORCEPROP 0 LASTPIN (6475 3025) $PN 130
J 0
(6485 3035);
DISPLAY 0.680851 (6485 3035);
PAINT MONO (6485 3035);
FORCEPROP 0 LASTPIN (6475 3075) $PN 132
J 0
(6485 3085);
DISPLAY 0.680851 (6485 3085);
PAINT MONO (6485 3085);
FORCEPROP 0 LASTPIN (6475 3125) $PN 134
J 0
(6485 3135);
DISPLAY 0.680851 (6485 3135);
PAINT MONO (6485 3135);
FORCEPROP 0 LASTPIN (6475 3175) $PN 136
J 0
(6485 3185);
DISPLAY 0.680851 (6485 3185);
PAINT MONO (6485 3185);
FORCEPROP 0 LASTPIN (6475 3225) $PN 139
J 0
(6485 3235);
DISPLAY 0.680851 (6485 3235);
PAINT MONO (6485 3235);
FORCEPROP 0 LASTPIN (6475 3275) $PN 141
J 0
(6485 3285);
DISPLAY 0.680851 (6485 3285);
PAINT MONO (6485 3285);
FORCEPROP 0 LASTPIN (6475 3325) $PN 143
J 0
(6485 3335);
DISPLAY 0.680851 (6485 3335);
PAINT MONO (6485 3335);
FORCEPROP 0 LASTPIN (5275 75) $PN 151
J 2
(5265 85);
DISPLAY 0.680851 (5265 85);
PAINT MONO (5265 85);
FORCEPROP 0 LASTPIN (5275 125) $PN 153
J 2
(5265 135);
DISPLAY 0.680851 (5265 135);
PAINT MONO (5265 135);
FORCEPROP 0 LASTPIN (5275 175) $PN 155
J 2
(5265 185);
DISPLAY 0.680851 (5265 185);
PAINT MONO (5265 185);
FORCEPROP 0 LASTPIN (5275 225) $PN 158
J 2
(5265 235);
DISPLAY 0.680851 (5265 235);
PAINT MONO (5265 235);
FORCEPROP 0 LASTPIN (5275 275) $PN 160
J 2
(5265 285);
DISPLAY 0.680851 (5265 285);
PAINT MONO (5265 285);
FORCEPROP 0 LASTPIN (5275 325) $PN 162
J 2
(5265 335);
DISPLAY 0.680851 (5265 335);
PAINT MONO (5265 335);
FORCEPROP 0 LASTPIN (5275 375) $PN 164
J 2
(5265 385);
DISPLAY 0.680851 (5265 385);
PAINT MONO (5265 385);
FORCEPROP 0 LASTPIN (5275 425) $PN 166
J 2
(5265 435);
DISPLAY 0.680851 (5265 435);
PAINT MONO (5265 435);
FORCEPROP 0 LASTPIN (5275 475) $PN 169
J 2
(5265 485);
DISPLAY 0.680851 (5265 485);
PAINT MONO (5265 485);
FORCEPROP 0 LASTPIN (5275 525) $PN 171
J 2
(5265 535);
DISPLAY 0.680851 (5265 535);
PAINT MONO (5265 535);
FORCEPROP 0 LASTPIN (5275 575) $PN 173
J 2
(5265 585);
DISPLAY 0.680851 (5265 585);
PAINT MONO (5265 585);
FORCEPROP 0 LASTPIN (5275 625) $PN 175
J 2
(5265 635);
DISPLAY 0.680851 (5265 635);
PAINT MONO (5265 635);
FORCEPROP 0 LASTPIN (5275 675) $PN 177
J 2
(5265 685);
DISPLAY 0.680851 (5265 685);
PAINT MONO (5265 685);
FORCEPROP 0 LASTPIN (5275 725) $PN 180
J 2
(5265 735);
DISPLAY 0.680851 (5265 735);
PAINT MONO (5265 735);
FORCEPROP 0 LASTPIN (5275 775) $PN 182
J 2
(5265 785);
DISPLAY 0.680851 (5265 785);
PAINT MONO (5265 785);
FORCEPROP 0 LASTPIN (5275 825) $PN 184
J 2
(5265 835);
DISPLAY 0.680851 (5265 835);
PAINT MONO (5265 835);
FORCEPROP 0 LASTPIN (5275 875) $PN 186
J 2
(5265 885);
DISPLAY 0.680851 (5265 885);
PAINT MONO (5265 885);
FORCEPROP 0 LASTPIN (5275 925) $PN 188
J 2
(5265 935);
DISPLAY 0.680851 (5265 935);
PAINT MONO (5265 935);
FORCEPROP 0 LASTPIN (5275 975) $PN 191
J 2
(5265 985);
DISPLAY 0.680851 (5265 985);
PAINT MONO (5265 985);
FORCEPROP 0 LASTPIN (5275 1025) $PN 193
J 2
(5265 1035);
DISPLAY 0.680851 (5265 1035);
PAINT MONO (5265 1035);
FORCEPROP 0 LASTPIN (5275 1075) $PN 195
J 2
(5265 1085);
DISPLAY 0.680851 (5265 1085);
PAINT MONO (5265 1085);
FORCEPROP 0 LASTPIN (5275 1125) $PN 197
J 2
(5265 1135);
DISPLAY 0.680851 (5265 1135);
PAINT MONO (5265 1135);
FORCEPROP 0 LASTPIN (5275 1175) $PN 199
J 2
(5265 1185);
DISPLAY 0.680851 (5265 1185);
PAINT MONO (5265 1185);
FORCEPROP 0 LASTPIN (5275 1225) $PN 202
J 2
(5265 1235);
DISPLAY 0.680851 (5265 1235);
PAINT MONO (5265 1235);
FORCEPROP 0 LASTPIN (5275 1275) $PN 204
J 2
(5265 1285);
DISPLAY 0.680851 (5265 1285);
PAINT MONO (5265 1285);
FORCEPROP 0 LASTPIN (5275 1325) $PN 206
J 2
(5265 1335);
DISPLAY 0.680851 (5265 1335);
PAINT MONO (5265 1335);
FORCEPROP 0 LASTPIN (5275 1375) $PN 208
J 2
(5265 1385);
DISPLAY 0.680851 (5265 1385);
PAINT MONO (5265 1385);
FORCEPROP 0 LASTPIN (5275 1425) $PN 210
J 2
(5265 1435);
DISPLAY 0.680851 (5265 1435);
PAINT MONO (5265 1435);
FORCEPROP 0 LASTPIN (5275 1475) $PN 212
J 2
(5265 1485);
DISPLAY 0.680851 (5265 1485);
PAINT MONO (5265 1485);
FORCEPROP 0 LASTPIN (5275 1525) $PN 214
J 2
(5265 1535);
DISPLAY 0.680851 (5265 1535);
PAINT MONO (5265 1535);
FORCEPROP 0 LASTPIN (5275 1575) $PN 216
J 2
(5265 1585);
DISPLAY 0.680851 (5265 1585);
PAINT MONO (5265 1585);
FORCEPROP 0 LASTPIN (5275 1625) $PN 219
J 2
(5265 1635);
DISPLAY 0.680851 (5265 1635);
PAINT MONO (5265 1635);
FORCEPROP 0 LASTPIN (5275 1675) $PN 222
J 2
(5265 1685);
DISPLAY 0.680851 (5265 1685);
PAINT MONO (5265 1685);
FORCEPROP 0 LASTPIN (5275 1725) $PN 224
J 2
(5265 1735);
DISPLAY 0.680851 (5265 1735);
PAINT MONO (5265 1735);
FORCEPROP 0 LASTPIN (5275 1775) $PN 226
J 2
(5265 1785);
DISPLAY 0.680851 (5265 1785);
PAINT MONO (5265 1785);
FORCEPROP 0 LASTPIN (5275 1825) $PN 228
J 2
(5265 1835);
DISPLAY 0.680851 (5265 1835);
PAINT MONO (5265 1835);
FORCEPROP 0 LASTPIN (5275 1875) $PN 230
J 2
(5265 1885);
DISPLAY 0.680851 (5265 1885);
PAINT MONO (5265 1885);
FORCEPROP 0 LASTPIN (5275 1925) $PN 233
J 2
(5265 1935);
DISPLAY 0.680851 (5265 1935);
PAINT MONO (5265 1935);
FORCEPROP 0 LASTPIN (5275 1975) $PN 235
J 2
(5265 1985);
DISPLAY 0.680851 (5265 1985);
PAINT MONO (5265 1985);
FORCEPROP 0 LASTPIN (5275 2025) $PN 237
J 2
(5265 2035);
DISPLAY 0.680851 (5265 2035);
PAINT MONO (5265 2035);
FORCEPROP 0 LASTPIN (5275 2075) $PN 240
J 2
(5265 2085);
DISPLAY 0.680851 (5265 2085);
PAINT MONO (5265 2085);
FORCEPROP 0 LASTPIN (5275 2125) $PN 242
J 2
(5265 2135);
DISPLAY 0.680851 (5265 2135);
PAINT MONO (5265 2135);
FORCEPROP 0 LASTPIN (5275 2175) $PN 244
J 2
(5265 2185);
DISPLAY 0.680851 (5265 2185);
PAINT MONO (5265 2185);
FORCEPROP 0 LASTPIN (5275 2225) $PN 246
J 2
(5265 2235);
DISPLAY 0.680851 (5265 2235);
PAINT MONO (5265 2235);
FORCEPROP 0 LASTPIN (5275 2275) $PN 248
J 2
(5265 2285);
DISPLAY 0.680851 (5265 2285);
PAINT MONO (5265 2285);
FORCEPROP 0 LASTPIN (5275 2325) $PN 251
J 2
(5265 2335);
DISPLAY 0.680851 (5265 2335);
PAINT MONO (5265 2335);
FORCEPROP 0 LASTPIN (5275 2375) $PN 253
J 2
(5265 2385);
DISPLAY 0.680851 (5265 2385);
PAINT MONO (5265 2385);
FORCEPROP 0 LASTPIN (5275 2425) $PN 255
J 2
(5265 2435);
DISPLAY 0.680851 (5265 2435);
PAINT MONO (5265 2435);
FORCEPROP 0 LASTPIN (5275 2475) $PN 257
J 2
(5265 2485);
DISPLAY 0.680851 (5265 2485);
PAINT MONO (5265 2485);
FORCEPROP 0 LASTPIN (5275 2525) $PN 259
J 2
(5265 2535);
DISPLAY 0.680851 (5265 2535);
PAINT MONO (5265 2535);
FORCEPROP 0 LASTPIN (5275 2575) $PN 262
J 2
(5265 2585);
DISPLAY 0.680851 (5265 2585);
PAINT MONO (5265 2585);
FORCEPROP 0 LASTPIN (5275 2625) $PN 264
J 2
(5265 2635);
DISPLAY 0.680851 (5265 2635);
PAINT MONO (5265 2635);
FORCEPROP 0 LASTPIN (5275 2675) $PN 266
J 2
(5265 2685);
DISPLAY 0.680851 (5265 2685);
PAINT MONO (5265 2685);
FORCEPROP 0 LASTPIN (5275 2725) $PN 268
J 2
(5265 2735);
DISPLAY 0.680851 (5265 2735);
PAINT MONO (5265 2735);
FORCEPROP 0 LASTPIN (5275 2775) $PN 270
J 2
(5265 2785);
DISPLAY 0.680851 (5265 2785);
PAINT MONO (5265 2785);
FORCEPROP 0 LASTPIN (5275 2825) $PN 273
J 2
(5265 2835);
DISPLAY 0.680851 (5265 2835);
PAINT MONO (5265 2835);
FORCEPROP 0 LASTPIN (5275 2875) $PN 275
J 2
(5265 2885);
DISPLAY 0.680851 (5265 2885);
PAINT MONO (5265 2885);
FORCEPROP 0 LASTPIN (5275 2925) $PN 277
J 2
(5265 2935);
DISPLAY 0.680851 (5265 2935);
PAINT MONO (5265 2935);
FORCEPROP 0 LASTPIN (5275 2975) $PN 279
J 2
(5265 2985);
DISPLAY 0.680851 (5265 2985);
PAINT MONO (5265 2985);
FORCEPROP 0 LASTPIN (5275 3025) $PN 281
J 2
(5265 3035);
DISPLAY 0.680851 (5265 3035);
PAINT MONO (5265 3035);
FORCEPROP 0 LASTPIN (5275 3075) $PN 284
J 2
(5265 3085);
DISPLAY 0.680851 (5265 3085);
PAINT MONO (5265 3085);
FORCEPROP 0 LASTPIN (5275 3125) $PN 286
J 2
(5265 3135);
DISPLAY 0.680851 (5265 3135);
PAINT MONO (5265 3135);
FORCEPROP 0 LASTPIN (5275 3175) $PN 288
J 2
(5265 3185);
DISPLAY 0.680851 (5265 3185);
PAINT MONO (5265 3185);
FORCEPROP 1 LAST NEEDS_NO_SIZE TRUE
J 0
(5875 1700);
DISPLAY 0.723404 (5875 1700);
PAINT GREEN (5875 1700);
DISPLAY INVISIBLE (5875 1700);
FORCEPROP 1 LAST CDS_LMAN_SYM_OUTLINE -450,1775,450,-1775
J 0
(5875 1700);
DISPLAY 0.468085 (5875 1700);
PAINT GREEN (5875 1700);
DISPLAY INVISIBLE (5875 1700);
FORCEPROP 2 LAST CDS_LIB pure_quanta
J 0
(5875 1700);
DISPLAY INVISIBLE (5875 1700);
FORCEPROP 2 LAST CDS_LOCATION J14
J 0
(5425 3825);
DISPLAY 1.021277 (5425 3825);
DISPLAY INVISIBLE (5425 3825);
FORCEPROP 0 LAST $SEC 3
J 0
(5425 3825);
DISPLAY 0.680851 (5425 3825);
PAINT MONO (5425 3825);
DISPLAY INVISIBLE (5425 3825);
FORCEPROP 2 LAST CDS_SEC 3
J 0
(5425 3825);
DISPLAY 1.021277 (5425 3825);
DISPLAY INVISIBLE (5425 3825);
FORCEPROP 1 LAST PATH I176
J 0
(5875 1700);
DISPLAY 0.723404 (5875 1700);
PAINT GREEN (5875 1700);
DISPLAY INVISIBLE (5875 1700);
FORCEADD UNIVERSAL_GND..1
(6725 -375);
FORCEPROP 3 LASTPIN (6725 -325) SIG_NAME GND\g
J 0
(6735 -315);
DISPLAY 0.659574 (6735 -315);
PAINT MONO (6735 -315);
DISPLAY INVISIBLE (6735 -315);
FORCEPROP 2 LAST CDS_LIB logical_power
J 0
(6725 -375);
PAINT MONO (6725 -375);
DISPLAY INVISIBLE (6725 -375);
FORCEPROP 1 LAST HDL_POWER GND
J 1
(6750 -450);
DISPLAY 0.872340 (6750 -450);
PAINT GREEN (6750 -450);
DISPLAY INVISIBLE (6750 -450);
FORCEPROP 1 LAST PATH I177
J 0
(6800 -375);
DISPLAY 0.872340 (6800 -375);
PAINT AQUA (6800 -375);
DISPLAY INVISIBLE (6800 -375);
FORCEADD SCONN288_ADR50017P087CC..2
(2475 2325);
FORCEPROP 1 LAST PART_NUMBER DFHST8FS460
J 0
(1870 3613);
DISPLAY 0.723404 (1870 3613);
PAINT GREEN (1870 3613);
DISPLAY INVISIBLE (1870 3613);
FORCEPROP 2 LAST PART_TYPE SMLF
J 0
(1875 3850);
DISPLAY 1.021277 (1875 3850);
FORCEPROP 1 LAST MATERIAL IO
J 0
(1870 3486);
DISPLAY 0.723404 (1870 3486);
PAINT GREEN (1870 3486);
FORCEPROP 2 LAST VALUE SCONN288_ADR50017-P087CC
J 0
(1875 3800);
DISPLAY 1.021277 (1875 3800);
FORCEPROP 1 LAST LOCATION J14
J 0
(1870 3760);
DISPLAY 0.723404 (1870 3760);
PAINT GREEN (1870 3760);
FORCEPROP 0 LASTPIN (3225 2375) $PN 12
J 0
(3235 2385);
DISPLAY 0.680851 (3235 2385);
PAINT MONO (3235 2385);
FORCEPROP 0 LASTPIN (3225 2425) $PN 11
J 0
(3235 2435);
DISPLAY 0.680851 (3235 2435);
PAINT MONO (3235 2435);
FORCEPROP 0 LASTPIN (3225 1325) $PN 105
J 0
(3235 1335);
DISPLAY 0.680851 (3235 1335);
PAINT MONO (3235 1335);
FORCEPROP 0 LASTPIN (3225 1375) $PN 104
J 0
(3235 1385);
DISPLAY 0.680851 (3235 1385);
PAINT MONO (3235 1385);
FORCEPROP 0 LASTPIN (3225 2475) $PN 23
J 0
(3235 2485);
DISPLAY 0.680851 (3235 2485);
PAINT MONO (3235 2485);
FORCEPROP 0 LASTPIN (3225 2525) $PN 22
J 0
(3235 2535);
DISPLAY 0.680851 (3235 2535);
PAINT MONO (3235 2535);
FORCEPROP 0 LASTPIN (3225 1425) $PN 116
J 0
(3235 1435);
DISPLAY 0.680851 (3235 1435);
PAINT MONO (3235 1435);
FORCEPROP 0 LASTPIN (3225 1475) $PN 115
J 0
(3235 1485);
DISPLAY 0.680851 (3235 1485);
PAINT MONO (3235 1485);
FORCEPROP 0 LASTPIN (3225 2575) $PN 34
J 0
(3235 2585);
DISPLAY 0.680851 (3235 2585);
PAINT MONO (3235 2585);
FORCEPROP 0 LASTPIN (3225 2625) $PN 33
J 0
(3235 2635);
DISPLAY 0.680851 (3235 2635);
PAINT MONO (3235 2635);
FORCEPROP 0 LASTPIN (3225 1525) $PN 127
J 0
(3235 1535);
DISPLAY 0.680851 (3235 1535);
PAINT MONO (3235 1535);
FORCEPROP 0 LASTPIN (3225 1575) $PN 126
J 0
(3235 1585);
DISPLAY 0.680851 (3235 1585);
PAINT MONO (3235 1585);
FORCEPROP 0 LASTPIN (3225 2675) $PN 45
J 0
(3235 2685);
DISPLAY 0.680851 (3235 2685);
PAINT MONO (3235 2685);
FORCEPROP 0 LASTPIN (3225 2725) $PN 44
J 0
(3235 2735);
DISPLAY 0.680851 (3235 2735);
PAINT MONO (3235 2735);
FORCEPROP 0 LASTPIN (3225 1625) $PN 138
J 0
(3235 1635);
DISPLAY 0.680851 (3235 1635);
PAINT MONO (3235 1635);
FORCEPROP 0 LASTPIN (3225 1675) $PN 137
J 0
(3235 1685);
DISPLAY 0.680851 (3235 1685);
PAINT MONO (3235 1685);
FORCEPROP 0 LASTPIN (3225 2775) $PN 56
J 0
(3235 2785);
DISPLAY 0.680851 (3235 2785);
PAINT MONO (3235 2785);
FORCEPROP 0 LASTPIN (3225 2825) $PN 55
J 0
(3235 2835);
DISPLAY 0.680851 (3235 2835);
PAINT MONO (3235 2835);
FORCEPROP 0 LASTPIN (3225 1725) $PN 238
J 0
(3235 1735);
DISPLAY 0.680851 (3235 1735);
PAINT MONO (3235 1735);
FORCEPROP 0 LASTPIN (3225 1775) $PN 239
J 0
(3235 1785);
DISPLAY 0.680851 (3235 1785);
PAINT MONO (3235 1785);
FORCEPROP 0 LASTPIN (3225 2875) $PN 156
J 0
(3235 2885);
DISPLAY 0.680851 (3235 2885);
PAINT MONO (3235 2885);
FORCEPROP 0 LASTPIN (3225 2925) $PN 157
J 0
(3235 2935);
DISPLAY 0.680851 (3235 2935);
PAINT MONO (3235 2935);
FORCEPROP 0 LASTPIN (3225 1825) $PN 249
J 0
(3235 1835);
DISPLAY 0.680851 (3235 1835);
PAINT MONO (3235 1835);
FORCEPROP 0 LASTPIN (3225 1875) $PN 250
J 0
(3235 1885);
DISPLAY 0.680851 (3235 1885);
PAINT MONO (3235 1885);
FORCEPROP 0 LASTPIN (3225 2975) $PN 167
J 0
(3235 2985);
DISPLAY 0.680851 (3235 2985);
PAINT MONO (3235 2985);
FORCEPROP 0 LASTPIN (3225 3025) $PN 168
J 0
(3235 3035);
DISPLAY 0.680851 (3235 3035);
PAINT MONO (3235 3035);
FORCEPROP 0 LASTPIN (3225 1925) $PN 260
J 0
(3235 1935);
DISPLAY 0.680851 (3235 1935);
PAINT MONO (3235 1935);
FORCEPROP 0 LASTPIN (3225 1975) $PN 261
J 0
(3235 1985);
DISPLAY 0.680851 (3235 1985);
PAINT MONO (3235 1985);
FORCEPROP 0 LASTPIN (3225 3075) $PN 178
J 0
(3235 3085);
DISPLAY 0.680851 (3235 3085);
PAINT MONO (3235 3085);
FORCEPROP 0 LASTPIN (3225 3125) $PN 179
J 0
(3235 3135);
DISPLAY 0.680851 (3235 3135);
PAINT MONO (3235 3135);
FORCEPROP 0 LASTPIN (3225 2025) $PN 271
J 0
(3235 2035);
DISPLAY 0.680851 (3235 2035);
PAINT MONO (3235 2035);
FORCEPROP 0 LASTPIN (3225 2075) $PN 272
J 0
(3235 2085);
DISPLAY 0.680851 (3235 2085);
PAINT MONO (3235 2085);
FORCEPROP 0 LASTPIN (3225 3175) $PN 189
J 0
(3235 3185);
DISPLAY 0.680851 (3235 3185);
PAINT MONO (3235 3185);
FORCEPROP 0 LASTPIN (3225 3225) $PN 190
J 0
(3235 3235);
DISPLAY 0.680851 (3235 3235);
PAINT MONO (3235 3235);
FORCEPROP 0 LASTPIN (3225 2125) $PN 282
J 0
(3235 2135);
DISPLAY 0.680851 (3235 2135);
PAINT MONO (3235 2135);
FORCEPROP 0 LASTPIN (3225 2175) $PN 283
J 0
(3235 2185);
DISPLAY 0.680851 (3235 2185);
PAINT MONO (3235 2185);
FORCEPROP 0 LASTPIN (3225 3275) $PN 200
J 0
(3235 3285);
DISPLAY 0.680851 (3235 3285);
PAINT MONO (3235 3285);
FORCEPROP 0 LASTPIN (3225 3325) $PN 201
J 0
(3235 3335);
DISPLAY 0.680851 (3235 3335);
PAINT MONO (3235 3335);
FORCEPROP 0 LASTPIN (3225 2225) $PN 94
J 0
(3235 2235);
DISPLAY 0.680851 (3235 2235);
PAINT MONO (3235 2235);
FORCEPROP 0 LASTPIN (3225 2275) $PN 93
J 0
(3235 2285);
DISPLAY 0.680851 (3235 2285);
PAINT MONO (3235 2285);
FORCEPROP 1 LAST NEEDS_NO_SIZE TRUE
J 0
(2475 2325);
DISPLAY 0.723404 (2475 2325);
PAINT GREEN (2475 2325);
DISPLAY INVISIBLE (2475 2325);
FORCEPROP 1 LAST CDS_LMAN_SYM_OUTLINE -600,1150,600,-1150
J 0
(2475 2325);
DISPLAY 0.468085 (2475 2325);
PAINT GREEN (2475 2325);
DISPLAY INVISIBLE (2475 2325);
FORCEPROP 2 LAST CDS_LIB pure_quanta
J 0
(2475 2325);
DISPLAY INVISIBLE (2475 2325);
FORCEPROP 0 LAST $SEC 2
J 0
(1875 3900);
DISPLAY 0.680851 (1875 3900);
PAINT MONO (1875 3900);
DISPLAY INVISIBLE (1875 3900);
FORCEPROP 0 LAST CDS_SEC 2
J 0
(1875 3900);
DISPLAY 1.021277 (1875 3900);
DISPLAY INVISIBLE (1875 3900);
FORCEPROP 1 LAST PATH I178
J 0
(2475 2325);
DISPLAY 0.723404 (2475 2325);
PAINT GREEN (2475 2325);
DISPLAY INVISIBLE (2475 2325);
FORCEADD Q_RES..1
(-2025 625);
FORCEPROP 1 LAST PART_NUMBER CS04992FB07
J 0
(-1925 600);
DISPLAY 0.404255 (-1925 600);
DISPLAY INVISIBLE (-1925 600);
FORCEPROP 1 LAST VALUE 49.9
J 2
(-1800 625);
DISPLAY 0.510638 (-1800 625);
FORCEPROP 1 LAST MATERIAL CHIP
J 0
(-2175 600);
DISPLAY 0.404255 (-2175 600);
FORCEPROP 1 LAST $LOCATION R3888
J 0
(-2250 625);
DISPLAY 0.638298 (-2250 625);
FORCEPROP 1 LASTPIN (-2125 625) $PN 1
J 0
(-2113 637);
DISPLAY 0.787234 (-2113 637);
PAINT MONO (-2113 637);
FORCEPROP 1 LASTPIN (-1925 625) $PN 2
J 0
(-1963 637);
DISPLAY 0.787234 (-1963 637);
PAINT MONO (-1963 637);
FORCEPROP 2 LAST CDS_LIB pure_quanta
J 0
(-2025 625);
DISPLAY INVISIBLE (-2025 625);
FORCEPROP 1 LAST PACK_TYPE 0402LF
J 0
(-1725 625);
DISPLAY 0.510638 (-1725 625);
DISPLAY INVISIBLE (-1725 625);
FORCEPROP 1 LAST TOLERANCE 1%
J 0
(-1800 625);
DISPLAY 0.510638 (-1800 625);
DISPLAY INVISIBLE (-1800 625);
FORCEPROP 1 LAST WATTAGE 1/16W
J 2
(-1725 575);
DISPLAY 0.404255 (-1725 575);
DISPLAY INVISIBLE (-1725 575);
FORCEPROP 0 LAST CDS_LOCATION R3888
J 0
(-2175 675);
DISPLAY 1.021277 (-2175 675);
DISPLAY INVISIBLE (-2175 675);
FORCEPROP 0 LAST $SEC 1
J 0
(-2175 675);
DISPLAY 0.680851 (-2175 675);
PAINT MONO (-2175 675);
DISPLAY INVISIBLE (-2175 675);
FORCEPROP 0 LAST CDS_SEC 1
J 0
(-2175 675);
DISPLAY 1.021277 (-2175 675);
DISPLAY INVISIBLE (-2175 675);
FORCEPROP 1 LAST PATH I179
J 0
(-2075 775);
DISPLAY 0.978723 (-2075 775);
PAINT WHITE (-2075 775);
DISPLAY INVISIBLE (-2075 775);
FORCEADD OFFPAGE..1
(-1975 2475);
FORCEPROP 2 LAST $XR1 94 
J 0
(-2286 2475);
DISPLAY 0.638298 (-2286 2475);
PAINT MONO (-2286 2475);
FORCEPROP 2 LAST $XR0 26 
J 0
(-2196 2475);
DISPLAY 0.638298 (-2196 2475);
PAINT MONO (-2196 2475);
FORCEPROP 2 LAST CDS_LIB standard
J 0
(-1975 2475);
PAINT MONO (-1975 2475);
DISPLAY INVISIBLE (-1975 2475);
FORCEPROP 1 LAST OFFPAGE TRUE
J 0
(-1650 2350);
DISPLAY 0.872340 (-1650 2350);
DISPLAY INVISIBLE (-1650 2350);
FORCEPROP 1 LAST COMMENT_BODY TRUE
J 0
(-1850 2375);
DISPLAY 0.872340 (-1850 2375);
PAINT GREEN (-1850 2375);
DISPLAY INVISIBLE (-1850 2375);
FORCEPROP 2 LAST PATH I18
J 0
(-1925 2550);
DISPLAY 1.021277 (-1925 2550);
DISPLAY INVISIBLE (-1925 2550);
FORCEADD OFFPAGE..1
(-825 550);
FORCEPROP 2 LAST $XR7 97 
J 0
(-1707 550);
DISPLAY 0.638298 (-1707 550);
PAINT MONO (-1707 550);
FORCEPROP 2 LAST $XR6 96 
J 0
(-1617 550);
DISPLAY 0.638298 (-1617 550);
PAINT MONO (-1617 550);
FORCEPROP 2 LAST $XR5 94 
J 0
(-1527 550);
DISPLAY 0.638298 (-1527 550);
PAINT MONO (-1527 550);
FORCEPROP 2 LAST $XR4 93 
J 0
(-1437 550);
DISPLAY 0.638298 (-1437 550);
PAINT MONO (-1437 550);
FORCEPROP 2 LAST $XR3 92 
J 0
(-1347 550);
DISPLAY 0.638298 (-1347 550);
PAINT MONO (-1347 550);
FORCEPROP 2 LAST $XR2 91 
J 0
(-1257 550);
DISPLAY 0.638298 (-1257 550);
PAINT MONO (-1257 550);
FORCEPROP 2 LAST $XR1 90 
J 0
(-1167 550);
DISPLAY 0.638298 (-1167 550);
PAINT MONO (-1167 550);
FORCEPROP 2 LAST $XR0 229 
J 0
(-1077 550);
DISPLAY 0.638298 (-1077 550);
PAINT MONO (-1077 550);
FORCEPROP 2 LAST CDS_LIB standard
J 2
(-825 550);
DISPLAY INVISIBLE (-825 550);
FORCEPROP 1 LAST OFFPAGE TRUE
J 0
(-500 425);
DISPLAY 0.872340 (-500 425);
DISPLAY INVISIBLE (-500 425);
FORCEPROP 1 LAST COMMENT_BODY TRUE
J 0
(-700 450);
DISPLAY 0.872340 (-700 450);
PAINT GREEN (-700 450);
DISPLAY INVISIBLE (-700 450);
FORCEPROP 2 LAST PATH I180
J 2
(-1000 625);
DISPLAY 1.021277 (-1000 625);
DISPLAY INVISIBLE (-1000 625);
FORCEADD OFFPAGE..1
(-1975 2525);
FORCEPROP 2 LAST $XR1 94 
J 0
(-2286 2525);
DISPLAY 0.638298 (-2286 2525);
PAINT MONO (-2286 2525);
FORCEPROP 2 LAST $XR0 26 
J 0
(-2196 2525);
DISPLAY 0.638298 (-2196 2525);
PAINT MONO (-2196 2525);
FORCEPROP 2 LAST CDS_LIB standard
J 0
(-1975 2525);
PAINT MONO (-1975 2525);
DISPLAY INVISIBLE (-1975 2525);
FORCEPROP 1 LAST OFFPAGE TRUE
J 0
(-1650 2400);
DISPLAY 0.872340 (-1650 2400);
DISPLAY INVISIBLE (-1650 2400);
FORCEPROP 1 LAST COMMENT_BODY TRUE
J 0
(-1850 2425);
DISPLAY 0.872340 (-1850 2425);
PAINT GREEN (-1850 2425);
DISPLAY INVISIBLE (-1850 2425);
FORCEPROP 2 LAST PATH I19
J 0
(-1925 2600);
DISPLAY 1.021277 (-1925 2600);
DISPLAY INVISIBLE (-1925 2600);
FORCEADD OFFPAGE..2
R 2
(-1975 -125);
FORCEPROP 2 LAST $XR0 26 
J 0
(-2199 -125);
DISPLAY 0.638298 (-2199 -125);
PAINT MONO (-2199 -125);
FORCEPROP 2 LAST CDS_LIB standard
J 0
(-1975 -125);
PAINT MONO (-1975 -125);
DISPLAY INVISIBLE (-1975 -125);
FORCEPROP 1 LAST OFFPAGE TRUE
J 2
(-2300 -250);
DISPLAY 0.872340 (-2300 -250);
DISPLAY INVISIBLE (-2300 -250);
FORCEPROP 1 LAST COMMENT_BODY TRUE
J 2
(-1930 -220);
DISPLAY 0.872340 (-1930 -220);
PAINT GREEN (-1930 -220);
DISPLAY INVISIBLE (-1930 -220);
FORCEPROP 2 LAST PATH I2
J 0
(-1925 -50);
DISPLAY 1.021277 (-1925 -50);
DISPLAY INVISIBLE (-1925 -50);
FORCEADD OFFPAGE..1
(-1975 2950);
FORCEPROP 2 LAST $XR1 94 
J 0
(-2286 2950);
DISPLAY 0.638298 (-2286 2950);
PAINT MONO (-2286 2950);
FORCEPROP 2 LAST $XR0 26 
J 0
(-2196 2950);
DISPLAY 0.638298 (-2196 2950);
PAINT MONO (-2196 2950);
FORCEPROP 2 LAST CDS_LIB standard
J 0
(-1975 2950);
PAINT MONO (-1975 2950);
DISPLAY INVISIBLE (-1975 2950);
FORCEPROP 1 LAST OFFPAGE TRUE
J 0
(-1650 2825);
DISPLAY 0.872340 (-1650 2825);
DISPLAY INVISIBLE (-1650 2825);
FORCEPROP 1 LAST COMMENT_BODY TRUE
J 0
(-1850 2850);
DISPLAY 0.872340 (-1850 2850);
PAINT GREEN (-1850 2850);
DISPLAY INVISIBLE (-1850 2850);
FORCEPROP 2 LAST PATH I20
J 0
(-1925 3025);
DISPLAY 1.021277 (-1925 3025);
DISPLAY INVISIBLE (-1925 3025);
FORCEADD VCC_CORE..1
(-1875 1200);
FORCEPROP 3 LASTPIN (-1875 1150) SIG_NAME P3V3_AUX\g
J 0
(-1865 1160);
DISPLAY 0.659574 (-1865 1160);
PAINT MONO (-1865 1160);
DISPLAY INVISIBLE (-1865 1160);
FORCEPROP 1 LAST HDL_POWER P3V3_AUX
J 1
(-1875 1250);
DISPLAY 1.148936 (-1875 1250);
PAINT GREEN (-1875 1250);
FORCEPROP 2 LAST CDS_LIB logical_power
J 0
(-1875 1200);
PAINT MONO (-1875 1200);
DISPLAY INVISIBLE (-1875 1200);
FORCEPROP 1 LAST PATH I21
J 0
(-1825 1225);
DISPLAY 0.872340 (-1825 1225);
PAINT AQUA (-1825 1225);
DISPLAY INVISIBLE (-1825 1225);
FORCEADD TAP..1
R 2
(-1050 1175);
FORCEPROP 3 LASTPIN (-1000 1175) SIG_NAME M_G_CPU0_SB_CB<1>
J 0
(-990 1185);
DISPLAY 0.659574 (-990 1185);
PAINT MONO (-990 1185);
DISPLAY INVISIBLE (-990 1185);
FORCEPROP 1 LASTPIN (-1000 1175) BN 1
J 2
(-988 1183);
DISPLAY 0.680851 (-988 1183);
PAINT GREEN (-988 1183);
FORCEPROP 2 LAST CDS_LIB standard
J 0
(-1050 1175);
DISPLAY INVISIBLE (-1050 1175);
FORCEPROP 1 LAST BODY_TYPE PLUMBING
J 2
(-1050 1225);
DISPLAY 0.872340 (-1050 1225);
PAINT GREEN (-1050 1225);
DISPLAY INVISIBLE (-1050 1225);
FORCEPROP 1 LAST HDL_TAP TRUE
J 2
(-1375 1050);
DISPLAY 0.872340 (-1375 1050);
DISPLAY INVISIBLE (-1375 1050);
FORCEPROP 1 LAST PATH I22
J 2
(-1048 1175);
DISPLAY 0.872340 (-1048 1175);
PAINT GREEN (-1048 1175);
DISPLAY INVISIBLE (-1048 1175);
FORCEADD TAP..1
R 2
(-1050 1125);
FORCEPROP 3 LASTPIN (-1000 1125) SIG_NAME M_G_CPU0_SB_CB<0>
J 0
(-990 1135);
DISPLAY 0.659574 (-990 1135);
PAINT MONO (-990 1135);
DISPLAY INVISIBLE (-990 1135);
FORCEPROP 1 LASTPIN (-1000 1125) BN 0
J 2
(-988 1133);
DISPLAY 0.680851 (-988 1133);
PAINT GREEN (-988 1133);
FORCEPROP 2 LAST CDS_LIB standard
J 0
(-1050 1125);
PAINT MONO (-1050 1125);
DISPLAY INVISIBLE (-1050 1125);
FORCEPROP 1 LAST BODY_TYPE PLUMBING
J 2
(-1050 1175);
DISPLAY 0.872340 (-1050 1175);
PAINT GREEN (-1050 1175);
DISPLAY INVISIBLE (-1050 1175);
FORCEPROP 1 LAST HDL_TAP TRUE
J 2
(-1375 1000);
DISPLAY 0.872340 (-1375 1000);
DISPLAY INVISIBLE (-1375 1000);
FORCEPROP 1 LAST PATH I23
J 2
(-1048 1125);
DISPLAY 0.872340 (-1048 1125);
PAINT GREEN (-1048 1125);
DISPLAY INVISIBLE (-1048 1125);
FORCEADD TAP..1
R 2
(-1050 1225);
FORCEPROP 3 LASTPIN (-1000 1225) SIG_NAME M_G_CPU0_SB_CB<2>
J 0
(-990 1235);
DISPLAY 0.659574 (-990 1235);
PAINT MONO (-990 1235);
DISPLAY INVISIBLE (-990 1235);
FORCEPROP 1 LASTPIN (-1000 1225) BN 2
J 2
(-988 1233);
DISPLAY 0.680851 (-988 1233);
PAINT GREEN (-988 1233);
FORCEPROP 2 LAST CDS_LIB standard
J 0
(-1050 1225);
DISPLAY INVISIBLE (-1050 1225);
FORCEPROP 1 LAST BODY_TYPE PLUMBING
J 2
(-1050 1275);
DISPLAY 0.872340 (-1050 1275);
PAINT GREEN (-1050 1275);
DISPLAY INVISIBLE (-1050 1275);
FORCEPROP 1 LAST HDL_TAP TRUE
J 2
(-1375 1100);
DISPLAY 0.872340 (-1375 1100);
DISPLAY INVISIBLE (-1375 1100);
FORCEPROP 1 LAST PATH I24
J 2
(-1048 1225);
DISPLAY 0.872340 (-1048 1225);
PAINT GREEN (-1048 1225);
DISPLAY INVISIBLE (-1048 1225);
FORCEADD TAP..1
R 2
(-1050 1275);
FORCEPROP 3 LASTPIN (-1000 1275) SIG_NAME M_G_CPU0_SB_CB<3>
J 0
(-990 1285);
DISPLAY 0.659574 (-990 1285);
PAINT MONO (-990 1285);
DISPLAY INVISIBLE (-990 1285);
FORCEPROP 1 LASTPIN (-1000 1275) BN 3
J 2
(-988 1283);
DISPLAY 0.680851 (-988 1283);
PAINT GREEN (-988 1283);
FORCEPROP 2 LAST CDS_LIB standard
J 0
(-1050 1275);
DISPLAY INVISIBLE (-1050 1275);
FORCEPROP 1 LAST BODY_TYPE PLUMBING
J 2
(-1050 1325);
DISPLAY 0.872340 (-1050 1325);
PAINT GREEN (-1050 1325);
DISPLAY INVISIBLE (-1050 1325);
FORCEPROP 1 LAST HDL_TAP TRUE
J 2
(-1375 1150);
DISPLAY 0.872340 (-1375 1150);
DISPLAY INVISIBLE (-1375 1150);
FORCEPROP 1 LAST PATH I25
J 2
(-1048 1275);
DISPLAY 0.872340 (-1048 1275);
PAINT GREEN (-1048 1275);
DISPLAY INVISIBLE (-1048 1275);
FORCEADD TAP..1
R 2
(-1050 1325);
FORCEPROP 3 LASTPIN (-1000 1325) SIG_NAME M_G_CPU0_SB_CB<4>
J 0
(-990 1335);
DISPLAY 0.659574 (-990 1335);
PAINT MONO (-990 1335);
DISPLAY INVISIBLE (-990 1335);
FORCEPROP 1 LASTPIN (-1000 1325) BN 4
J 2
(-988 1333);
DISPLAY 0.680851 (-988 1333);
PAINT GREEN (-988 1333);
FORCEPROP 2 LAST CDS_LIB standard
J 0
(-1050 1325);
DISPLAY INVISIBLE (-1050 1325);
FORCEPROP 1 LAST BODY_TYPE PLUMBING
J 2
(-1050 1375);
DISPLAY 0.872340 (-1050 1375);
PAINT GREEN (-1050 1375);
DISPLAY INVISIBLE (-1050 1375);
FORCEPROP 1 LAST HDL_TAP TRUE
J 2
(-1375 1200);
DISPLAY 0.872340 (-1375 1200);
DISPLAY INVISIBLE (-1375 1200);
FORCEPROP 1 LAST PATH I26
J 2
(-1048 1325);
DISPLAY 0.872340 (-1048 1325);
PAINT GREEN (-1048 1325);
DISPLAY INVISIBLE (-1048 1325);
FORCEADD TAP..1
R 2
(-1050 1375);
FORCEPROP 3 LASTPIN (-1000 1375) SIG_NAME M_G_CPU0_SB_CB<5>
J 0
(-990 1385);
DISPLAY 0.659574 (-990 1385);
PAINT MONO (-990 1385);
DISPLAY INVISIBLE (-990 1385);
FORCEPROP 1 LASTPIN (-1000 1375) BN 5
J 2
(-988 1383);
DISPLAY 0.680851 (-988 1383);
PAINT GREEN (-988 1383);
FORCEPROP 2 LAST CDS_LIB standard
J 0
(-1050 1375);
DISPLAY INVISIBLE (-1050 1375);
FORCEPROP 1 LAST BODY_TYPE PLUMBING
J 2
(-1050 1425);
DISPLAY 0.872340 (-1050 1425);
PAINT GREEN (-1050 1425);
DISPLAY INVISIBLE (-1050 1425);
FORCEPROP 1 LAST HDL_TAP TRUE
J 2
(-1375 1250);
DISPLAY 0.872340 (-1375 1250);
DISPLAY INVISIBLE (-1375 1250);
FORCEPROP 1 LAST PATH I27
J 2
(-1048 1375);
DISPLAY 0.872340 (-1048 1375);
PAINT GREEN (-1048 1375);
DISPLAY INVISIBLE (-1048 1375);
FORCEADD TAP..1
R 2
(-1050 1425);
FORCEPROP 3 LASTPIN (-1000 1425) SIG_NAME M_G_CPU0_SB_CB<6>
J 0
(-990 1435);
DISPLAY 0.659574 (-990 1435);
PAINT MONO (-990 1435);
DISPLAY INVISIBLE (-990 1435);
FORCEPROP 1 LASTPIN (-1000 1425) BN 6
J 2
(-988 1433);
DISPLAY 0.680851 (-988 1433);
PAINT GREEN (-988 1433);
FORCEPROP 2 LAST CDS_LIB standard
J 0
(-1050 1425);
DISPLAY INVISIBLE (-1050 1425);
FORCEPROP 1 LAST BODY_TYPE PLUMBING
J 2
(-1050 1475);
DISPLAY 0.872340 (-1050 1475);
PAINT GREEN (-1050 1475);
DISPLAY INVISIBLE (-1050 1475);
FORCEPROP 1 LAST HDL_TAP TRUE
J 2
(-1375 1300);
DISPLAY 0.872340 (-1375 1300);
DISPLAY INVISIBLE (-1375 1300);
FORCEPROP 1 LAST PATH I28
J 2
(-1048 1425);
DISPLAY 0.872340 (-1048 1425);
PAINT GREEN (-1048 1425);
DISPLAY INVISIBLE (-1048 1425);
FORCEADD TAP..1
R 2
(-1050 1575);
FORCEPROP 3 LASTPIN (-1000 1575) SIG_NAME M_G_CPU0_SA_CB<0>
J 0
(-990 1585);
DISPLAY 0.659574 (-990 1585);
PAINT MONO (-990 1585);
DISPLAY INVISIBLE (-990 1585);
FORCEPROP 1 LASTPIN (-1000 1575) BN 0
J 2
(-988 1583);
DISPLAY 0.680851 (-988 1583);
PAINT GREEN (-988 1583);
FORCEPROP 2 LAST CDS_LIB standard
J 0
(-1050 1575);
PAINT MONO (-1050 1575);
DISPLAY INVISIBLE (-1050 1575);
FORCEPROP 1 LAST BODY_TYPE PLUMBING
J 2
(-1050 1625);
DISPLAY 0.872340 (-1050 1625);
PAINT GREEN (-1050 1625);
DISPLAY INVISIBLE (-1050 1625);
FORCEPROP 1 LAST HDL_TAP TRUE
J 2
(-1375 1450);
DISPLAY 0.872340 (-1375 1450);
DISPLAY INVISIBLE (-1375 1450);
FORCEPROP 1 LAST PATH I29
J 2
(-1048 1575);
DISPLAY 0.872340 (-1048 1575);
PAINT GREEN (-1048 1575);
DISPLAY INVISIBLE (-1048 1575);
FORCEADD OFFPAGE..2
R 2
(-1975 -75);
FORCEPROP 2 LAST $XR0 26 
J 0
(-2199 -75);
DISPLAY 0.638298 (-2199 -75);
PAINT MONO (-2199 -75);
FORCEPROP 2 LAST CDS_LIB standard
J 0
(-1975 -75);
PAINT MONO (-1975 -75);
DISPLAY INVISIBLE (-1975 -75);
FORCEPROP 1 LAST OFFPAGE TRUE
J 2
(-2300 -200);
DISPLAY 0.872340 (-2300 -200);
DISPLAY INVISIBLE (-2300 -200);
FORCEPROP 1 LAST COMMENT_BODY TRUE
J 2
(-1930 -170);
DISPLAY 0.872340 (-1930 -170);
PAINT GREEN (-1930 -170);
DISPLAY INVISIBLE (-1930 -170);
FORCEPROP 2 LAST PATH I3
J 0
(-1925 0);
DISPLAY 1.021277 (-1925 0);
DISPLAY INVISIBLE (-1925 0);
FORCEADD TAP..1
R 2
(-1050 1475);
FORCEPROP 3 LASTPIN (-1000 1475) SIG_NAME M_G_CPU0_SB_CB<7>
J 0
(-990 1485);
DISPLAY 0.659574 (-990 1485);
PAINT MONO (-990 1485);
DISPLAY INVISIBLE (-990 1485);
FORCEPROP 1 LASTPIN (-1000 1475) BN 7
J 2
(-988 1483);
DISPLAY 0.680851 (-988 1483);
PAINT GREEN (-988 1483);
FORCEPROP 2 LAST CDS_LIB standard
J 0
(-1050 1475);
DISPLAY INVISIBLE (-1050 1475);
FORCEPROP 1 LAST BODY_TYPE PLUMBING
J 2
(-1050 1525);
DISPLAY 0.872340 (-1050 1525);
PAINT GREEN (-1050 1525);
DISPLAY INVISIBLE (-1050 1525);
FORCEPROP 1 LAST HDL_TAP TRUE
J 2
(-1375 1350);
DISPLAY 0.872340 (-1375 1350);
DISPLAY INVISIBLE (-1375 1350);
FORCEPROP 1 LAST PATH I30
J 2
(-1048 1475);
DISPLAY 0.872340 (-1048 1475);
PAINT GREEN (-1048 1475);
DISPLAY INVISIBLE (-1048 1475);
FORCEADD TAP..1
R 2
(-1050 1675);
FORCEPROP 3 LASTPIN (-1000 1675) SIG_NAME M_G_CPU0_SA_CB<2>
J 0
(-990 1685);
DISPLAY 0.659574 (-990 1685);
PAINT MONO (-990 1685);
DISPLAY INVISIBLE (-990 1685);
FORCEPROP 1 LASTPIN (-1000 1675) BN 2
J 2
(-988 1683);
DISPLAY 0.680851 (-988 1683);
PAINT GREEN (-988 1683);
FORCEPROP 2 LAST CDS_LIB standard
J 0
(-1050 1675);
DISPLAY INVISIBLE (-1050 1675);
FORCEPROP 1 LAST BODY_TYPE PLUMBING
J 2
(-1050 1725);
DISPLAY 0.872340 (-1050 1725);
PAINT GREEN (-1050 1725);
DISPLAY INVISIBLE (-1050 1725);
FORCEPROP 1 LAST HDL_TAP TRUE
J 2
(-1375 1550);
DISPLAY 0.872340 (-1375 1550);
DISPLAY INVISIBLE (-1375 1550);
FORCEPROP 1 LAST PATH I31
J 2
(-1048 1675);
DISPLAY 0.872340 (-1048 1675);
PAINT GREEN (-1048 1675);
DISPLAY INVISIBLE (-1048 1675);
FORCEADD TAP..1
R 2
(-1050 1625);
FORCEPROP 3 LASTPIN (-1000 1625) SIG_NAME M_G_CPU0_SA_CB<1>
J 0
(-990 1635);
DISPLAY 0.659574 (-990 1635);
PAINT MONO (-990 1635);
DISPLAY INVISIBLE (-990 1635);
FORCEPROP 1 LASTPIN (-1000 1625) BN 1
J 2
(-988 1633);
DISPLAY 0.680851 (-988 1633);
PAINT GREEN (-988 1633);
FORCEPROP 2 LAST CDS_LIB standard
J 0
(-1050 1625);
DISPLAY INVISIBLE (-1050 1625);
FORCEPROP 1 LAST BODY_TYPE PLUMBING
J 2
(-1050 1675);
DISPLAY 0.872340 (-1050 1675);
PAINT GREEN (-1050 1675);
DISPLAY INVISIBLE (-1050 1675);
FORCEPROP 1 LAST HDL_TAP TRUE
J 2
(-1375 1500);
DISPLAY 0.872340 (-1375 1500);
DISPLAY INVISIBLE (-1375 1500);
FORCEPROP 1 LAST PATH I32
J 2
(-1048 1625);
DISPLAY 0.872340 (-1048 1625);
PAINT GREEN (-1048 1625);
DISPLAY INVISIBLE (-1048 1625);
FORCEADD TAP..1
R 2
(-1050 1725);
FORCEPROP 3 LASTPIN (-1000 1725) SIG_NAME M_G_CPU0_SA_CB<3>
J 0
(-990 1735);
DISPLAY 0.659574 (-990 1735);
PAINT MONO (-990 1735);
DISPLAY INVISIBLE (-990 1735);
FORCEPROP 1 LASTPIN (-1000 1725) BN 3
J 2
(-988 1733);
DISPLAY 0.680851 (-988 1733);
PAINT GREEN (-988 1733);
FORCEPROP 2 LAST CDS_LIB standard
J 0
(-1050 1725);
DISPLAY INVISIBLE (-1050 1725);
FORCEPROP 1 LAST BODY_TYPE PLUMBING
J 2
(-1050 1775);
DISPLAY 0.872340 (-1050 1775);
PAINT GREEN (-1050 1775);
DISPLAY INVISIBLE (-1050 1775);
FORCEPROP 1 LAST HDL_TAP TRUE
J 2
(-1375 1600);
DISPLAY 0.872340 (-1375 1600);
DISPLAY INVISIBLE (-1375 1600);
FORCEPROP 1 LAST PATH I33
J 2
(-1048 1725);
DISPLAY 0.872340 (-1048 1725);
PAINT GREEN (-1048 1725);
DISPLAY INVISIBLE (-1048 1725);
FORCEADD TAP..1
R 2
(-1050 1775);
FORCEPROP 3 LASTPIN (-1000 1775) SIG_NAME M_G_CPU0_SA_CB<4>
J 0
(-990 1785);
DISPLAY 0.659574 (-990 1785);
PAINT MONO (-990 1785);
DISPLAY INVISIBLE (-990 1785);
FORCEPROP 1 LASTPIN (-1000 1775) BN 4
J 2
(-988 1783);
DISPLAY 0.680851 (-988 1783);
PAINT GREEN (-988 1783);
FORCEPROP 2 LAST CDS_LIB standard
J 0
(-1050 1775);
DISPLAY INVISIBLE (-1050 1775);
FORCEPROP 1 LAST BODY_TYPE PLUMBING
J 2
(-1050 1825);
DISPLAY 0.872340 (-1050 1825);
PAINT GREEN (-1050 1825);
DISPLAY INVISIBLE (-1050 1825);
FORCEPROP 1 LAST HDL_TAP TRUE
J 2
(-1375 1650);
DISPLAY 0.872340 (-1375 1650);
DISPLAY INVISIBLE (-1375 1650);
FORCEPROP 1 LAST PATH I34
J 2
(-1048 1775);
DISPLAY 0.872340 (-1048 1775);
PAINT GREEN (-1048 1775);
DISPLAY INVISIBLE (-1048 1775);
FORCEADD TAP..1
R 2
(-1050 1825);
FORCEPROP 3 LASTPIN (-1000 1825) SIG_NAME M_G_CPU0_SA_CB<5>
J 0
(-990 1835);
DISPLAY 0.659574 (-990 1835);
PAINT MONO (-990 1835);
DISPLAY INVISIBLE (-990 1835);
FORCEPROP 1 LASTPIN (-1000 1825) BN 5
J 2
(-988 1833);
DISPLAY 0.680851 (-988 1833);
PAINT GREEN (-988 1833);
FORCEPROP 2 LAST CDS_LIB standard
J 0
(-1050 1825);
DISPLAY INVISIBLE (-1050 1825);
FORCEPROP 1 LAST BODY_TYPE PLUMBING
J 2
(-1050 1875);
DISPLAY 0.872340 (-1050 1875);
PAINT GREEN (-1050 1875);
DISPLAY INVISIBLE (-1050 1875);
FORCEPROP 1 LAST HDL_TAP TRUE
J 2
(-1375 1700);
DISPLAY 0.872340 (-1375 1700);
DISPLAY INVISIBLE (-1375 1700);
FORCEPROP 1 LAST PATH I35
J 2
(-1048 1825);
DISPLAY 0.872340 (-1048 1825);
PAINT GREEN (-1048 1825);
DISPLAY INVISIBLE (-1048 1825);
FORCEADD TAP..1
R 2
(-1050 1925);
FORCEPROP 3 LASTPIN (-1000 1925) SIG_NAME M_G_CPU0_SA_CB<7>
J 0
(-990 1935);
DISPLAY 0.659574 (-990 1935);
PAINT MONO (-990 1935);
DISPLAY INVISIBLE (-990 1935);
FORCEPROP 1 LASTPIN (-1000 1925) BN 7
J 2
(-988 1933);
DISPLAY 0.680851 (-988 1933);
PAINT GREEN (-988 1933);
FORCEPROP 2 LAST CDS_LIB standard
J 0
(-1050 1925);
DISPLAY INVISIBLE (-1050 1925);
FORCEPROP 1 LAST BODY_TYPE PLUMBING
J 2
(-1050 1975);
DISPLAY 0.872340 (-1050 1975);
PAINT GREEN (-1050 1975);
DISPLAY INVISIBLE (-1050 1975);
FORCEPROP 1 LAST HDL_TAP TRUE
J 2
(-1375 1800);
DISPLAY 0.872340 (-1375 1800);
DISPLAY INVISIBLE (-1375 1800);
FORCEPROP 1 LAST PATH I36
J 2
(-1048 1925);
DISPLAY 0.872340 (-1048 1925);
PAINT GREEN (-1048 1925);
DISPLAY INVISIBLE (-1048 1925);
FORCEADD TAP..1
R 2
(-1050 1875);
FORCEPROP 3 LASTPIN (-1000 1875) SIG_NAME M_G_CPU0_SA_CB<6>
J 0
(-990 1885);
DISPLAY 0.659574 (-990 1885);
PAINT MONO (-990 1885);
DISPLAY INVISIBLE (-990 1885);
FORCEPROP 1 LASTPIN (-1000 1875) BN 6
J 2
(-988 1883);
DISPLAY 0.680851 (-988 1883);
PAINT GREEN (-988 1883);
FORCEPROP 2 LAST CDS_LIB standard
J 0
(-1050 1875);
DISPLAY INVISIBLE (-1050 1875);
FORCEPROP 1 LAST BODY_TYPE PLUMBING
J 2
(-1050 1925);
DISPLAY 0.872340 (-1050 1925);
PAINT GREEN (-1050 1925);
DISPLAY INVISIBLE (-1050 1925);
FORCEPROP 1 LAST HDL_TAP TRUE
J 2
(-1375 1750);
DISPLAY 0.872340 (-1375 1750);
DISPLAY INVISIBLE (-1375 1750);
FORCEPROP 1 LAST PATH I37
J 2
(-1048 1875);
DISPLAY 0.872340 (-1048 1875);
PAINT GREEN (-1048 1875);
DISPLAY INVISIBLE (-1048 1875);
FORCEADD TAP..1
R 2
(-1050 2625);
FORCEPROP 3 LASTPIN (-1000 2625) SIG_NAME M_G_CPU0_SB_CA<0>
J 0
(-990 2635);
DISPLAY 0.659574 (-990 2635);
PAINT MONO (-990 2635);
DISPLAY INVISIBLE (-990 2635);
FORCEPROP 1 LASTPIN (-1000 2625) BN 0
J 2
(-988 2633);
DISPLAY 0.680851 (-988 2633);
PAINT GREEN (-988 2633);
FORCEPROP 2 LAST CDS_LIB standard
J 0
(-1050 2625);
DISPLAY INVISIBLE (-1050 2625);
FORCEPROP 1 LAST BODY_TYPE PLUMBING
J 2
(-1050 2675);
DISPLAY 0.872340 (-1050 2675);
PAINT GREEN (-1050 2675);
DISPLAY INVISIBLE (-1050 2675);
FORCEPROP 1 LAST HDL_TAP TRUE
J 2
(-1375 2500);
DISPLAY 0.872340 (-1375 2500);
DISPLAY INVISIBLE (-1375 2500);
FORCEPROP 1 LAST PATH I38
J 2
(-1048 2625);
DISPLAY 0.872340 (-1048 2625);
PAINT GREEN (-1048 2625);
DISPLAY INVISIBLE (-1048 2625);
FORCEADD TAP..1
R 2
(-1050 2675);
FORCEPROP 3 LASTPIN (-1000 2675) SIG_NAME M_G_CPU0_SB_CA<1>
J 0
(-990 2685);
DISPLAY 0.659574 (-990 2685);
PAINT MONO (-990 2685);
DISPLAY INVISIBLE (-990 2685);
FORCEPROP 1 LASTPIN (-1000 2675) BN 1
J 2
(-988 2683);
DISPLAY 0.680851 (-988 2683);
PAINT GREEN (-988 2683);
FORCEPROP 2 LAST CDS_LIB standard
J 0
(-1050 2675);
DISPLAY INVISIBLE (-1050 2675);
FORCEPROP 1 LAST BODY_TYPE PLUMBING
J 2
(-1050 2725);
DISPLAY 0.872340 (-1050 2725);
PAINT GREEN (-1050 2725);
DISPLAY INVISIBLE (-1050 2725);
FORCEPROP 1 LAST HDL_TAP TRUE
J 2
(-1375 2550);
DISPLAY 0.872340 (-1375 2550);
DISPLAY INVISIBLE (-1375 2550);
FORCEPROP 1 LAST PATH I39
J 2
(-1048 2675);
DISPLAY 0.872340 (-1048 2675);
PAINT GREEN (-1048 2675);
DISPLAY INVISIBLE (-1048 2675);
FORCEADD OFFPAGE..3
R 2
(-1975 475);
FORCEPROP 2 LAST $XR0 114 
J 0
(-2255 475);
DISPLAY 0.638298 (-2255 475);
PAINT MONO (-2255 475);
FORCEPROP 2 LAST CDS_LIB standard
J 0
(-1975 475);
PAINT MONO (-1975 475);
DISPLAY INVISIBLE (-1975 475);
FORCEPROP 1 LAST OFFPAGE TRUE
J 2
(-2300 350);
DISPLAY 0.872340 (-2300 350);
DISPLAY INVISIBLE (-2300 350);
FORCEPROP 1 LAST COMMENT_BODY TRUE
J 2
(-1925 375);
DISPLAY 0.872340 (-1925 375);
PAINT GREEN (-1925 375);
DISPLAY INVISIBLE (-1925 375);
FORCEPROP 2 LAST PATH I4
J 0
(-1925 550);
DISPLAY 1.021277 (-1925 550);
DISPLAY INVISIBLE (-1925 550);
FORCEADD TAP..1
R 2
(-1050 2725);
FORCEPROP 3 LASTPIN (-1000 2725) SIG_NAME M_G_CPU0_SB_CA<2>
J 0
(-990 2735);
DISPLAY 0.659574 (-990 2735);
PAINT MONO (-990 2735);
DISPLAY INVISIBLE (-990 2735);
FORCEPROP 1 LASTPIN (-1000 2725) BN 2
J 2
(-988 2733);
DISPLAY 0.680851 (-988 2733);
PAINT GREEN (-988 2733);
FORCEPROP 2 LAST CDS_LIB standard
J 0
(-1050 2725);
DISPLAY INVISIBLE (-1050 2725);
FORCEPROP 1 LAST BODY_TYPE PLUMBING
J 2
(-1050 2775);
DISPLAY 0.872340 (-1050 2775);
PAINT GREEN (-1050 2775);
DISPLAY INVISIBLE (-1050 2775);
FORCEPROP 1 LAST HDL_TAP TRUE
J 2
(-1375 2600);
DISPLAY 0.872340 (-1375 2600);
DISPLAY INVISIBLE (-1375 2600);
FORCEPROP 1 LAST PATH I40
J 2
(-1048 2725);
DISPLAY 0.872340 (-1048 2725);
PAINT GREEN (-1048 2725);
DISPLAY INVISIBLE (-1048 2725);
FORCEADD TAP..1
R 2
(-1050 2775);
FORCEPROP 3 LASTPIN (-1000 2775) SIG_NAME M_G_CPU0_SB_CA<3>
J 0
(-990 2785);
DISPLAY 0.659574 (-990 2785);
PAINT MONO (-990 2785);
DISPLAY INVISIBLE (-990 2785);
FORCEPROP 1 LASTPIN (-1000 2775) BN 3
J 2
(-988 2783);
DISPLAY 0.680851 (-988 2783);
PAINT GREEN (-988 2783);
FORCEPROP 2 LAST CDS_LIB standard
J 0
(-1050 2775);
DISPLAY INVISIBLE (-1050 2775);
FORCEPROP 1 LAST BODY_TYPE PLUMBING
J 2
(-1050 2825);
DISPLAY 0.872340 (-1050 2825);
PAINT GREEN (-1050 2825);
DISPLAY INVISIBLE (-1050 2825);
FORCEPROP 1 LAST HDL_TAP TRUE
J 2
(-1375 2650);
DISPLAY 0.872340 (-1375 2650);
DISPLAY INVISIBLE (-1375 2650);
FORCEPROP 1 LAST PATH I41
J 2
(-1048 2775);
DISPLAY 0.872340 (-1048 2775);
PAINT GREEN (-1048 2775);
DISPLAY INVISIBLE (-1048 2775);
FORCEADD TAP..1
R 2
(-1050 2825);
FORCEPROP 3 LASTPIN (-1000 2825) SIG_NAME M_G_CPU0_SB_CA<4>
J 0
(-990 2835);
DISPLAY 0.659574 (-990 2835);
PAINT MONO (-990 2835);
DISPLAY INVISIBLE (-990 2835);
FORCEPROP 1 LASTPIN (-1000 2825) BN 4
J 2
(-988 2833);
DISPLAY 0.680851 (-988 2833);
PAINT GREEN (-988 2833);
FORCEPROP 2 LAST CDS_LIB standard
J 0
(-1050 2825);
DISPLAY INVISIBLE (-1050 2825);
FORCEPROP 1 LAST BODY_TYPE PLUMBING
J 2
(-1050 2875);
DISPLAY 0.872340 (-1050 2875);
PAINT GREEN (-1050 2875);
DISPLAY INVISIBLE (-1050 2875);
FORCEPROP 1 LAST HDL_TAP TRUE
J 2
(-1375 2700);
DISPLAY 0.872340 (-1375 2700);
DISPLAY INVISIBLE (-1375 2700);
FORCEPROP 1 LAST PATH I42
J 2
(-1048 2825);
DISPLAY 0.872340 (-1048 2825);
PAINT GREEN (-1048 2825);
DISPLAY INVISIBLE (-1048 2825);
FORCEADD TAP..1
R 2
(-1050 2925);
FORCEPROP 3 LASTPIN (-1000 2925) SIG_NAME M_G_CPU0_SB_CA<6>
J 0
(-990 2935);
DISPLAY 0.659574 (-990 2935);
PAINT MONO (-990 2935);
DISPLAY INVISIBLE (-990 2935);
FORCEPROP 1 LASTPIN (-1000 2925) BN 6
J 2
(-988 2933);
DISPLAY 0.680851 (-988 2933);
PAINT GREEN (-988 2933);
FORCEPROP 2 LAST CDS_LIB standard
J 0
(-1050 2925);
DISPLAY INVISIBLE (-1050 2925);
FORCEPROP 1 LAST BODY_TYPE PLUMBING
J 2
(-1050 2975);
DISPLAY 0.872340 (-1050 2975);
PAINT GREEN (-1050 2975);
DISPLAY INVISIBLE (-1050 2975);
FORCEPROP 1 LAST HDL_TAP TRUE
J 2
(-1375 2800);
DISPLAY 0.872340 (-1375 2800);
DISPLAY INVISIBLE (-1375 2800);
FORCEPROP 1 LAST PATH I43
J 2
(-1048 2925);
DISPLAY 0.872340 (-1048 2925);
PAINT GREEN (-1048 2925);
DISPLAY INVISIBLE (-1048 2925);
FORCEADD TAP..1
R 2
(-1050 2875);
FORCEPROP 3 LASTPIN (-1000 2875) SIG_NAME M_G_CPU0_SB_CA<5>
J 0
(-990 2885);
DISPLAY 0.659574 (-990 2885);
PAINT MONO (-990 2885);
DISPLAY INVISIBLE (-990 2885);
FORCEPROP 1 LASTPIN (-1000 2875) BN 5
J 2
(-988 2883);
DISPLAY 0.680851 (-988 2883);
PAINT GREEN (-988 2883);
FORCEPROP 2 LAST CDS_LIB standard
J 0
(-1050 2875);
DISPLAY INVISIBLE (-1050 2875);
FORCEPROP 1 LAST BODY_TYPE PLUMBING
J 2
(-1050 2925);
DISPLAY 0.872340 (-1050 2925);
PAINT GREEN (-1050 2925);
DISPLAY INVISIBLE (-1050 2925);
FORCEPROP 1 LAST HDL_TAP TRUE
J 2
(-1375 2750);
DISPLAY 0.872340 (-1375 2750);
DISPLAY INVISIBLE (-1375 2750);
FORCEPROP 1 LAST PATH I44
J 2
(-1048 2875);
DISPLAY 0.872340 (-1048 2875);
PAINT GREEN (-1048 2875);
DISPLAY INVISIBLE (-1048 2875);
FORCEADD UNIVERSAL_GND..1
(-825 -1050);
FORCEPROP 3 LASTPIN (-825 -1000) SIG_NAME GND\g
J 0
(-815 -990);
DISPLAY 0.659574 (-815 -990);
PAINT MONO (-815 -990);
DISPLAY INVISIBLE (-815 -990);
FORCEPROP 2 LAST CDS_LIB logical_power
J 0
(-825 -1050);
PAINT MONO (-825 -1050);
DISPLAY INVISIBLE (-825 -1050);
FORCEPROP 1 LAST HDL_POWER GND
J 1
(-800 -1125);
DISPLAY 0.872340 (-800 -1125);
PAINT GREEN (-800 -1125);
DISPLAY INVISIBLE (-800 -1125);
FORCEPROP 1 LAST PATH I45
J 0
(-750 -1050);
DISPLAY 0.872340 (-750 -1050);
PAINT AQUA (-750 -1050);
DISPLAY INVISIBLE (-750 -1050);
FORCEADD Q_RES..2
(-825 -825);
FORCEPROP 1 LAST PART_NUMBER CS38452FB05
J 0
(-785 -950);
DISPLAY 0.978723 (-785 -950);
DISPLAY INVISIBLE (-785 -950);
FORCEPROP 1 LAST VALUE 84.5K
J 0
(-780 -750);
DISPLAY 0.978723 (-780 -750);
FORCEPROP 1 LAST WATTAGE 1/16W
J 0
(-785 -850);
DISPLAY 0.978723 (-785 -850);
FORCEPROP 1 LAST MATERIAL CHIP
J 0
(-785 -900);
DISPLAY 0.978723 (-785 -900);
FORCEPROP 1 LAST TOLERANCE 1%
J 0
(-780 -800);
DISPLAY 0.978723 (-780 -800);
FORCEPROP 1 LAST PACK_TYPE 0402LF
J 0
(-785 -1000);
DISPLAY 0.978723 (-785 -1000);
FORCEPROP 1 LAST $LOCATION R39
J 0
(-780 -700);
DISPLAY 0.978723 (-780 -700);
FORCEPROP 1 LASTPIN (-825 -725) $PN 1
J 0
(-820 -763);
DISPLAY 0.787234 (-820 -763);
FORCEPROP 1 LASTPIN (-825 -925) $PN 2
J 0
(-820 -915);
DISPLAY 0.787234 (-820 -915);
FORCEPROP 2 LAST CDS_LIB pure_quanta
J 0
(-825 -825);
PAINT MONO (-825 -825);
DISPLAY INVISIBLE (-825 -825);
FORCEPROP 2 LAST CDS_LOCATION R39
J 0
(-775 -600);
DISPLAY 1.021277 (-775 -600);
DISPLAY INVISIBLE (-775 -600);
FORCEPROP 2 LAST $SEC 1
J 0
(-775 -600);
DISPLAY 0.680851 (-775 -600);
PAINT MONO (-775 -600);
DISPLAY INVISIBLE (-775 -600);
FORCEPROP 2 LAST CDS_SEC 1
J 0
(-775 -600);
DISPLAY 1.021277 (-775 -600);
DISPLAY INVISIBLE (-775 -600);
FORCEPROP 1 LAST PATH I46
J 0
(-775 -650);
DISPLAY 0.978723 (-775 -650);
PAINT WHITE (-775 -650);
DISPLAY INVISIBLE (-775 -650);
FORCEADD SCONN288_ADR50017P087CC..1
(-225 1600);
FORCEPROP 1 LAST PART_NUMBER DFHST8FS460
J 0
(-670 3610);
DISPLAY 0.723404 (-670 3610);
PAINT GREEN (-670 3610);
DISPLAY INVISIBLE (-670 3610);
FORCEPROP 1 LAST MATERIAL IO
J 0
(-670 3483);
DISPLAY 0.723404 (-670 3483);
PAINT GREEN (-670 3483);
FORCEPROP 2 LAST PART_TYPE SMLF
J 0
(-675 3775);
DISPLAY 1.021277 (-675 3775);
FORCEPROP 2 LAST VALUE SCONN288_ADR50017-P087CC
J 0
(-675 3725);
DISPLAY 1.021277 (-675 3725);
FORCEPROP 1 LAST $LOCATION J14
J 0
(-675 3675);
DISPLAY 0.723404 (-675 3675);
PAINT GREEN (-675 3675);
FORCEPROP 0 LASTPIN (-825 975) $PN 62
J 2
(-835 985);
DISPLAY 0.680851 (-835 985);
PAINT MONO (-835 985);
FORCEPROP 0 LASTPIN (-825 3025) $PN 66
J 2
(-835 3035);
DISPLAY 0.680851 (-835 3035);
PAINT MONO (-835 3035);
FORCEPROP 0 LASTPIN (-825 2625) $PN 76
J 2
(-835 2635);
DISPLAY 0.680851 (-835 2635);
PAINT MONO (-835 2635);
FORCEPROP 0 LASTPIN (-825 3075) $PN 211
J 2
(-835 3085);
DISPLAY 0.680851 (-835 3085);
PAINT MONO (-835 3085);
FORCEPROP 0 LASTPIN (-825 2675) $PN 221
J 2
(-835 2685);
DISPLAY 0.680851 (-835 2685);
PAINT MONO (-835 2685);
FORCEPROP 0 LASTPIN (-825 3125) $PN 68
J 2
(-835 3135);
DISPLAY 0.680851 (-835 3135);
PAINT MONO (-835 3135);
FORCEPROP 0 LASTPIN (-825 2725) $PN 78
J 2
(-835 2735);
DISPLAY 0.680851 (-835 2735);
PAINT MONO (-835 2735);
FORCEPROP 0 LASTPIN (-825 3175) $PN 213
J 2
(-835 3185);
DISPLAY 0.680851 (-835 3185);
PAINT MONO (-835 3185);
FORCEPROP 0 LASTPIN (-825 2775) $PN 223
J 2
(-835 2785);
DISPLAY 0.680851 (-835 2785);
PAINT MONO (-835 2785);
FORCEPROP 0 LASTPIN (-825 3225) $PN 70
J 2
(-835 3235);
DISPLAY 0.680851 (-835 3235);
PAINT MONO (-835 3235);
FORCEPROP 0 LASTPIN (-825 2825) $PN 80
J 2
(-835 2835);
DISPLAY 0.680851 (-835 2835);
PAINT MONO (-835 2835);
FORCEPROP 0 LASTPIN (-825 3275) $PN 215
J 2
(-835 3285);
DISPLAY 0.680851 (-835 3285);
PAINT MONO (-835 3285);
FORCEPROP 0 LASTPIN (-825 2875) $PN 225
J 2
(-835 2885);
DISPLAY 0.680851 (-835 2885);
PAINT MONO (-835 2885);
FORCEPROP 0 LASTPIN (-825 3325) $PN 72
J 2
(-835 3335);
DISPLAY 0.680851 (-835 3335);
PAINT MONO (-835 3335);
FORCEPROP 0 LASTPIN (-825 2925) $PN 82
J 2
(-835 2935);
DISPLAY 0.680851 (-835 2935);
PAINT MONO (-835 2935);
FORCEPROP 0 LASTPIN (-825 1575) $PN 51
J 2
(-835 1585);
DISPLAY 0.680851 (-835 1585);
PAINT MONO (-835 1585);
FORCEPROP 0 LASTPIN (-825 1125) $PN 96
J 2
(-835 1135);
DISPLAY 0.680851 (-835 1135);
PAINT MONO (-835 1135);
FORCEPROP 0 LASTPIN (-825 1625) $PN 53
J 2
(-835 1635);
DISPLAY 0.680851 (-835 1635);
PAINT MONO (-835 1635);
FORCEPROP 0 LASTPIN (-825 1175) $PN 98
J 2
(-835 1185);
DISPLAY 0.680851 (-835 1185);
PAINT MONO (-835 1185);
FORCEPROP 0 LASTPIN (-825 1675) $PN 196
J 2
(-835 1685);
DISPLAY 0.680851 (-835 1685);
PAINT MONO (-835 1685);
FORCEPROP 0 LASTPIN (-825 1225) $PN 241
J 2
(-835 1235);
DISPLAY 0.680851 (-835 1235);
PAINT MONO (-835 1235);
FORCEPROP 0 LASTPIN (-825 1725) $PN 198
J 2
(-835 1735);
DISPLAY 0.680851 (-835 1735);
PAINT MONO (-835 1735);
FORCEPROP 0 LASTPIN (-825 1275) $PN 243
J 2
(-835 1285);
DISPLAY 0.680851 (-835 1285);
PAINT MONO (-835 1285);
FORCEPROP 0 LASTPIN (-825 1775) $PN 58
J 2
(-835 1785);
DISPLAY 0.680851 (-835 1785);
PAINT MONO (-835 1785);
FORCEPROP 0 LASTPIN (-825 1325) $PN 89
J 2
(-835 1335);
DISPLAY 0.680851 (-835 1335);
PAINT MONO (-835 1335);
FORCEPROP 0 LASTPIN (-825 1825) $PN 60
J 2
(-835 1835);
DISPLAY 0.680851 (-835 1835);
PAINT MONO (-835 1835);
FORCEPROP 0 LASTPIN (-825 1375) $PN 91
J 2
(-835 1385);
DISPLAY 0.680851 (-835 1385);
PAINT MONO (-835 1385);
FORCEPROP 0 LASTPIN (-825 1875) $PN 203
J 2
(-835 1885);
DISPLAY 0.680851 (-835 1885);
PAINT MONO (-835 1885);
FORCEPROP 0 LASTPIN (-825 1425) $PN 234
J 2
(-835 1435);
DISPLAY 0.680851 (-835 1435);
PAINT MONO (-835 1435);
FORCEPROP 0 LASTPIN (-825 1925) $PN 205
J 2
(-835 1935);
DISPLAY 0.680851 (-835 1935);
PAINT MONO (-835 1935);
FORCEPROP 0 LASTPIN (-825 1475) $PN 236
J 2
(-835 1485);
DISPLAY 0.680851 (-835 1485);
PAINT MONO (-835 1485);
FORCEPROP 0 LASTPIN (-825 2025) $PN 218
J 2
(-835 2035);
DISPLAY 0.680851 (-835 2035);
PAINT MONO (-835 2035);
FORCEPROP 0 LASTPIN (-825 2075) $PN 217
J 2
(-835 2085);
DISPLAY 0.680851 (-835 2085);
PAINT MONO (-835 2085);
FORCEPROP 0 LASTPIN (-825 2325) $PN 64
J 2
(-835 2335);
DISPLAY 0.680851 (-835 2335);
PAINT MONO (-835 2335);
FORCEPROP 0 LASTPIN (-825 2175) $PN 84
J 2
(-835 2185);
DISPLAY 0.680851 (-835 2185);
PAINT MONO (-835 2185);
FORCEPROP 0 LASTPIN (-825 2375) $PN 209
J 2
(-835 2385);
DISPLAY 0.680851 (-835 2385);
PAINT MONO (-835 2385);
FORCEPROP 0 LASTPIN (-825 2225) $PN 229
J 2
(-835 2235);
DISPLAY 0.680851 (-835 2235);
PAINT MONO (-835 2235);
FORCEPROP 0 LASTPIN (375 1775) $PN 7
J 0
(385 1785);
DISPLAY 0.680851 (385 1785);
PAINT MONO (385 1785);
FORCEPROP 0 LASTPIN (375 125) $PN 100
J 0
(385 135);
DISPLAY 0.680851 (385 135);
PAINT MONO (385 135);
FORCEPROP 0 LASTPIN (375 1825) $PN 9
J 0
(385 1835);
DISPLAY 0.680851 (385 1835);
PAINT MONO (385 1835);
FORCEPROP 0 LASTPIN (375 175) $PN 102
J 0
(385 185);
DISPLAY 0.680851 (385 185);
PAINT MONO (385 185);
FORCEPROP 0 LASTPIN (375 1875) $PN 152
J 0
(385 1885);
DISPLAY 0.680851 (385 1885);
PAINT MONO (385 1885);
FORCEPROP 0 LASTPIN (375 225) $PN 245
J 0
(385 235);
DISPLAY 0.680851 (385 235);
PAINT MONO (385 235);
FORCEPROP 0 LASTPIN (375 1925) $PN 154
J 0
(385 1935);
DISPLAY 0.680851 (385 1935);
PAINT MONO (385 1935);
FORCEPROP 0 LASTPIN (375 275) $PN 247
J 0
(385 285);
DISPLAY 0.680851 (385 285);
PAINT MONO (385 285);
FORCEPROP 0 LASTPIN (375 1975) $PN 14
J 0
(385 1985);
DISPLAY 0.680851 (385 1985);
PAINT MONO (385 1985);
FORCEPROP 0 LASTPIN (375 325) $PN 107
J 0
(385 335);
DISPLAY 0.680851 (385 335);
PAINT MONO (385 335);
FORCEPROP 0 LASTPIN (375 2025) $PN 16
J 0
(385 2035);
DISPLAY 0.680851 (385 2035);
PAINT MONO (385 2035);
FORCEPROP 0 LASTPIN (375 375) $PN 109
J 0
(385 385);
DISPLAY 0.680851 (385 385);
PAINT MONO (385 385);
FORCEPROP 0 LASTPIN (375 2075) $PN 159
J 0
(385 2085);
DISPLAY 0.680851 (385 2085);
PAINT MONO (385 2085);
FORCEPROP 0 LASTPIN (375 425) $PN 252
J 0
(385 435);
DISPLAY 0.680851 (385 435);
PAINT MONO (385 435);
FORCEPROP 0 LASTPIN (375 2125) $PN 161
J 0
(385 2135);
DISPLAY 0.680851 (385 2135);
PAINT MONO (385 2135);
FORCEPROP 0 LASTPIN (375 475) $PN 254
J 0
(385 485);
DISPLAY 0.680851 (385 485);
PAINT MONO (385 485);
FORCEPROP 0 LASTPIN (375 2175) $PN 18
J 0
(385 2185);
DISPLAY 0.680851 (385 2185);
PAINT MONO (385 2185);
FORCEPROP 0 LASTPIN (375 525) $PN 111
J 0
(385 535);
DISPLAY 0.680851 (385 535);
PAINT MONO (385 535);
FORCEPROP 0 LASTPIN (375 2225) $PN 20
J 0
(385 2235);
DISPLAY 0.680851 (385 2235);
PAINT MONO (385 2235);
FORCEPROP 0 LASTPIN (375 575) $PN 113
J 0
(385 585);
DISPLAY 0.680851 (385 585);
PAINT MONO (385 585);
FORCEPROP 0 LASTPIN (375 2275) $PN 163
J 0
(385 2285);
DISPLAY 0.680851 (385 2285);
PAINT MONO (385 2285);
FORCEPROP 0 LASTPIN (375 625) $PN 256
J 0
(385 635);
DISPLAY 0.680851 (385 635);
PAINT MONO (385 635);
FORCEPROP 0 LASTPIN (375 2325) $PN 165
J 0
(385 2335);
DISPLAY 0.680851 (385 2335);
PAINT MONO (385 2335);
FORCEPROP 0 LASTPIN (375 675) $PN 258
J 0
(385 685);
DISPLAY 0.680851 (385 685);
PAINT MONO (385 685);
FORCEPROP 0 LASTPIN (375 2375) $PN 25
J 0
(385 2385);
DISPLAY 0.680851 (385 2385);
PAINT MONO (385 2385);
FORCEPROP 0 LASTPIN (375 725) $PN 118
J 0
(385 735);
DISPLAY 0.680851 (385 735);
PAINT MONO (385 735);
FORCEPROP 0 LASTPIN (375 2425) $PN 27
J 0
(385 2435);
DISPLAY 0.680851 (385 2435);
PAINT MONO (385 2435);
FORCEPROP 0 LASTPIN (375 775) $PN 120
J 0
(385 785);
DISPLAY 0.680851 (385 785);
PAINT MONO (385 785);
FORCEPROP 0 LASTPIN (375 2475) $PN 170
J 0
(385 2485);
DISPLAY 0.680851 (385 2485);
PAINT MONO (385 2485);
FORCEPROP 0 LASTPIN (375 825) $PN 263
J 0
(385 835);
DISPLAY 0.680851 (385 835);
PAINT MONO (385 835);
FORCEPROP 0 LASTPIN (375 2525) $PN 172
J 0
(385 2535);
DISPLAY 0.680851 (385 2535);
PAINT MONO (385 2535);
FORCEPROP 0 LASTPIN (375 875) $PN 265
J 0
(385 885);
DISPLAY 0.680851 (385 885);
PAINT MONO (385 885);
FORCEPROP 0 LASTPIN (375 2575) $PN 29
J 0
(385 2585);
DISPLAY 0.680851 (385 2585);
PAINT MONO (385 2585);
FORCEPROP 0 LASTPIN (375 925) $PN 122
J 0
(385 935);
DISPLAY 0.680851 (385 935);
PAINT MONO (385 935);
FORCEPROP 0 LASTPIN (375 2625) $PN 31
J 0
(385 2635);
DISPLAY 0.680851 (385 2635);
PAINT MONO (385 2635);
FORCEPROP 0 LASTPIN (375 975) $PN 124
J 0
(385 985);
DISPLAY 0.680851 (385 985);
PAINT MONO (385 985);
FORCEPROP 0 LASTPIN (375 2675) $PN 174
J 0
(385 2685);
DISPLAY 0.680851 (385 2685);
PAINT MONO (385 2685);
FORCEPROP 0 LASTPIN (375 1025) $PN 267
J 0
(385 1035);
DISPLAY 0.680851 (385 1035);
PAINT MONO (385 1035);
FORCEPROP 0 LASTPIN (375 2725) $PN 176
J 0
(385 2735);
DISPLAY 0.680851 (385 2735);
PAINT MONO (385 2735);
FORCEPROP 0 LASTPIN (375 1075) $PN 269
J 0
(385 1085);
DISPLAY 0.680851 (385 1085);
PAINT MONO (385 1085);
FORCEPROP 0 LASTPIN (375 2775) $PN 36
J 0
(385 2785);
DISPLAY 0.680851 (385 2785);
PAINT MONO (385 2785);
FORCEPROP 0 LASTPIN (375 1125) $PN 129
J 0
(385 1135);
DISPLAY 0.680851 (385 1135);
PAINT MONO (385 1135);
FORCEPROP 0 LASTPIN (375 2825) $PN 38
J 0
(385 2835);
DISPLAY 0.680851 (385 2835);
PAINT MONO (385 2835);
FORCEPROP 0 LASTPIN (375 1175) $PN 131
J 0
(385 1185);
DISPLAY 0.680851 (385 1185);
PAINT MONO (385 1185);
FORCEPROP 0 LASTPIN (375 2875) $PN 181
J 0
(385 2885);
DISPLAY 0.680851 (385 2885);
PAINT MONO (385 2885);
FORCEPROP 0 LASTPIN (375 1225) $PN 274
J 0
(385 1235);
DISPLAY 0.680851 (385 1235);
PAINT MONO (385 1235);
FORCEPROP 0 LASTPIN (375 2925) $PN 183
J 0
(385 2935);
DISPLAY 0.680851 (385 2935);
PAINT MONO (385 2935);
FORCEPROP 0 LASTPIN (375 1275) $PN 276
J 0
(385 1285);
DISPLAY 0.680851 (385 1285);
PAINT MONO (385 1285);
FORCEPROP 0 LASTPIN (375 2975) $PN 40
J 0
(385 2985);
DISPLAY 0.680851 (385 2985);
PAINT MONO (385 2985);
FORCEPROP 0 LASTPIN (375 1325) $PN 133
J 0
(385 1335);
DISPLAY 0.680851 (385 1335);
PAINT MONO (385 1335);
FORCEPROP 0 LASTPIN (375 3025) $PN 42
J 0
(385 3035);
DISPLAY 0.680851 (385 3035);
PAINT MONO (385 3035);
FORCEPROP 0 LASTPIN (375 1375) $PN 135
J 0
(385 1385);
DISPLAY 0.680851 (385 1385);
PAINT MONO (385 1385);
FORCEPROP 0 LASTPIN (375 3075) $PN 185
J 0
(385 3085);
DISPLAY 0.680851 (385 3085);
PAINT MONO (385 3085);
FORCEPROP 0 LASTPIN (375 1425) $PN 278
J 0
(385 1435);
DISPLAY 0.680851 (385 1435);
PAINT MONO (385 1435);
FORCEPROP 0 LASTPIN (375 3125) $PN 187
J 0
(385 3135);
DISPLAY 0.680851 (385 3135);
PAINT MONO (385 3135);
FORCEPROP 0 LASTPIN (375 1475) $PN 280
J 0
(385 1485);
DISPLAY 0.680851 (385 1485);
PAINT MONO (385 1485);
FORCEPROP 0 LASTPIN (375 3175) $PN 47
J 0
(385 3185);
DISPLAY 0.680851 (385 3185);
PAINT MONO (385 3185);
FORCEPROP 0 LASTPIN (375 1525) $PN 140
J 0
(385 1535);
DISPLAY 0.680851 (385 1535);
PAINT MONO (385 1535);
FORCEPROP 0 LASTPIN (375 3225) $PN 49
J 0
(385 3235);
DISPLAY 0.680851 (385 3235);
PAINT MONO (385 3235);
FORCEPROP 0 LASTPIN (375 1575) $PN 142
J 0
(385 1585);
DISPLAY 0.680851 (385 1585);
PAINT MONO (385 1585);
FORCEPROP 0 LASTPIN (375 3275) $PN 192
J 0
(385 3285);
DISPLAY 0.680851 (385 3285);
PAINT MONO (385 3285);
FORCEPROP 0 LASTPIN (375 1625) $PN 285
J 0
(385 1635);
DISPLAY 0.680851 (385 1635);
PAINT MONO (385 1635);
FORCEPROP 0 LASTPIN (375 3325) $PN 194
J 0
(385 3335);
DISPLAY 0.680851 (385 3335);
PAINT MONO (385 3335);
FORCEPROP 0 LASTPIN (375 1675) $PN 287
J 0
(385 1685);
DISPLAY 0.680851 (385 1685);
PAINT MONO (385 1685);
FORCEPROP 0 LASTPIN (-825 825) $PN 148
J 2
(-835 835);
DISPLAY 0.680851 (-835 835);
PAINT MONO (-835 835);
FORCEPROP 0 LASTPIN (-825 725) $PN 4
J 2
(-835 735);
DISPLAY 0.680851 (-835 735);
PAINT MONO (-835 735);
FORCEPROP 0 LASTPIN (-825 775) $PN 5
J 2
(-835 785);
DISPLAY 0.680851 (-835 785);
PAINT MONO (-835 785);
FORCEPROP 0 LASTPIN (-825 -75) $PN 86
J 2
(-835 -65);
DISPLAY 0.680851 (-835 -65);
PAINT MONO (-835 -65);
FORCEPROP 0 LASTPIN (-825 -125) $PN 87
J 2
(-835 -115);
DISPLAY 0.680851 (-835 -115);
PAINT MONO (-835 -115);
FORCEPROP 0 LASTPIN (-825 2525) $PN 74
J 2
(-835 2535);
DISPLAY 0.680851 (-835 2535);
PAINT MONO (-835 2535);
FORCEPROP 0 LASTPIN (-825 2475) $PN 227
J 2
(-835 2485);
DISPLAY 0.680851 (-835 2485);
PAINT MONO (-835 2485);
FORCEPROP 0 LASTPIN (-825 475) $PN 147
J 2
(-835 485);
DISPLAY 0.680851 (-835 485);
PAINT MONO (-835 485);
FORCEPROP 0 LASTPIN (-825 1025) $PN 207
J 2
(-835 1035);
DISPLAY 0.680851 (-835 1035);
PAINT MONO (-835 1035);
FORCEPROP 0 LASTPIN (-825 75) $PN 2
J 2
(-835 85);
DISPLAY 0.680851 (-835 85);
PAINT MONO (-835 85);
FORCEPROP 0 LASTPIN (-825 125) $PN 144
J 2
(-835 135);
DISPLAY 0.680851 (-835 135);
PAINT MONO (-835 135);
FORCEPROP 0 LASTPIN (-825 175) $PN 149
J 2
(-835 185);
DISPLAY 0.680851 (-835 185);
PAINT MONO (-835 185);
FORCEPROP 0 LASTPIN (-825 225) $PN 150
J 2
(-835 235);
DISPLAY 0.680851 (-835 235);
PAINT MONO (-835 235);
FORCEPROP 0 LASTPIN (-825 275) $PN 220
J 2
(-835 285);
DISPLAY 0.680851 (-835 285);
PAINT MONO (-835 285);
FORCEPROP 0 LASTPIN (-825 325) $PN 231
J 2
(-835 335);
DISPLAY 0.680851 (-835 335);
PAINT MONO (-835 335);
FORCEPROP 0 LASTPIN (-825 375) $PN 232
J 2
(-835 385);
DISPLAY 0.680851 (-835 385);
PAINT MONO (-835 385);
FORCEPROP 0 LASTPIN (-825 875) $PN 3
J 2
(-835 885);
DISPLAY 0.680851 (-835 885);
PAINT MONO (-835 885);
FORCEPROP 1 LAST NEEDS_NO_SIZE TRUE
J 0
(-225 1600);
DISPLAY 0.723404 (-225 1600);
PAINT GREEN (-225 1600);
DISPLAY INVISIBLE (-225 1600);
FORCEPROP 1 LAST CDS_LMAN_SYM_OUTLINE -450,1875,450,-1875
J 0
(-225 1600);
DISPLAY 0.468085 (-225 1600);
PAINT GREEN (-225 1600);
DISPLAY INVISIBLE (-225 1600);
FORCEPROP 2 LAST CDS_LIB pure_quanta
J 0
(-225 1600);
DISPLAY INVISIBLE (-225 1600);
FORCEPROP 2 LAST CDS_LOCATION J14
J 0
(-675 3825);
DISPLAY 1.021277 (-675 3825);
DISPLAY INVISIBLE (-675 3825);
FORCEPROP 0 LAST $SEC 1
J 0
(-675 3825);
DISPLAY 0.680851 (-675 3825);
PAINT MONO (-675 3825);
DISPLAY INVISIBLE (-675 3825);
FORCEPROP 2 LAST CDS_SEC 1
J 0
(-675 3825);
DISPLAY 1.021277 (-675 3825);
DISPLAY INVISIBLE (-675 3825);
FORCEPROP 1 LAST PATH I47
J 0
(-225 1600);
DISPLAY 0.723404 (-225 1600);
PAINT GREEN (-225 1600);
DISPLAY INVISIBLE (-225 1600);
FORCEADD TAP..1
(600 175);
FORCEPROP 3 LASTPIN (550 175) SIG_NAME M_G_CPU0_SB_DQ<1>
J 0
(560 185);
DISPLAY 0.659574 (560 185);
PAINT MONO (560 185);
DISPLAY INVISIBLE (560 185);
FORCEPROP 1 LASTPIN (550 175) BN 1
J 0
(538 183);
DISPLAY 0.680851 (538 183);
PAINT GREEN (538 183);
FORCEPROP 2 LAST CDS_LIB standard
J 0
(600 175);
PAINT MONO (600 175);
DISPLAY INVISIBLE (600 175);
FORCEPROP 1 LAST BODY_TYPE PLUMBING
J 0
(600 225);
DISPLAY 0.872340 (600 225);
PAINT GREEN (600 225);
DISPLAY INVISIBLE (600 225);
FORCEPROP 1 LAST HDL_TAP TRUE
J 0
(925 50);
DISPLAY 0.872340 (925 50);
DISPLAY INVISIBLE (925 50);
FORCEPROP 1 LAST PATH I48
J 0
(598 175);
DISPLAY 0.872340 (598 175);
PAINT GREEN (598 175);
DISPLAY INVISIBLE (598 175);
FORCEADD TAP..1
(600 125);
FORCEPROP 3 LASTPIN (550 125) SIG_NAME M_G_CPU0_SB_DQ<0>
J 0
(560 135);
DISPLAY 0.659574 (560 135);
PAINT MONO (560 135);
DISPLAY INVISIBLE (560 135);
FORCEPROP 1 LASTPIN (550 125) BN 0
J 0
(538 133);
DISPLAY 0.680851 (538 133);
PAINT GREEN (538 133);
FORCEPROP 2 LAST CDS_LIB standard
J 0
(600 125);
PAINT MONO (600 125);
DISPLAY INVISIBLE (600 125);
FORCEPROP 1 LAST BODY_TYPE PLUMBING
J 0
(600 175);
DISPLAY 0.872340 (600 175);
PAINT GREEN (600 175);
DISPLAY INVISIBLE (600 175);
FORCEPROP 1 LAST HDL_TAP TRUE
J 0
(925 0);
DISPLAY 0.872340 (925 0);
DISPLAY INVISIBLE (925 0);
FORCEPROP 1 LAST PATH I49
J 0
(598 125);
DISPLAY 0.872340 (598 125);
PAINT GREEN (598 125);
DISPLAY INVISIBLE (598 125);
FORCEADD TAP..1
(600 225);
FORCEPROP 3 LASTPIN (550 225) SIG_NAME M_G_CPU0_SB_DQ<2>
J 0
(560 235);
DISPLAY 0.659574 (560 235);
PAINT MONO (560 235);
DISPLAY INVISIBLE (560 235);
FORCEPROP 1 LASTPIN (550 225) BN 2
J 0
(538 233);
DISPLAY 0.680851 (538 233);
PAINT GREEN (538 233);
FORCEPROP 2 LAST CDS_LIB standard
J 0
(600 225);
PAINT MONO (600 225);
DISPLAY INVISIBLE (600 225);
FORCEPROP 1 LAST BODY_TYPE PLUMBING
J 0
(600 275);
DISPLAY 0.872340 (600 275);
PAINT GREEN (600 275);
DISPLAY INVISIBLE (600 275);
FORCEPROP 1 LAST HDL_TAP TRUE
J 0
(925 100);
DISPLAY 0.872340 (925 100);
DISPLAY INVISIBLE (925 100);
FORCEPROP 1 LAST PATH I50
J 0
(598 225);
DISPLAY 0.872340 (598 225);
PAINT GREEN (598 225);
DISPLAY INVISIBLE (598 225);
FORCEADD TAP..1
(600 275);
FORCEPROP 3 LASTPIN (550 275) SIG_NAME M_G_CPU0_SB_DQ<3>
J 0
(560 285);
DISPLAY 0.659574 (560 285);
PAINT MONO (560 285);
DISPLAY INVISIBLE (560 285);
FORCEPROP 1 LASTPIN (550 275) BN 3
J 0
(538 283);
DISPLAY 0.680851 (538 283);
PAINT GREEN (538 283);
FORCEPROP 2 LAST CDS_LIB standard
J 0
(600 275);
PAINT MONO (600 275);
DISPLAY INVISIBLE (600 275);
FORCEPROP 1 LAST BODY_TYPE PLUMBING
J 0
(600 325);
DISPLAY 0.872340 (600 325);
PAINT GREEN (600 325);
DISPLAY INVISIBLE (600 325);
FORCEPROP 1 LAST HDL_TAP TRUE
J 0
(925 150);
DISPLAY 0.872340 (925 150);
DISPLAY INVISIBLE (925 150);
FORCEPROP 1 LAST PATH I51
J 0
(598 275);
DISPLAY 0.872340 (598 275);
PAINT GREEN (598 275);
DISPLAY INVISIBLE (598 275);
FORCEADD TAP..1
(600 425);
FORCEPROP 3 LASTPIN (550 425) SIG_NAME M_G_CPU0_SB_DQ<6>
J 0
(560 435);
DISPLAY 0.659574 (560 435);
PAINT MONO (560 435);
DISPLAY INVISIBLE (560 435);
FORCEPROP 1 LASTPIN (550 425) BN 6
J 0
(538 433);
DISPLAY 0.680851 (538 433);
PAINT GREEN (538 433);
FORCEPROP 2 LAST CDS_LIB standard
J 0
(600 425);
PAINT MONO (600 425);
DISPLAY INVISIBLE (600 425);
FORCEPROP 1 LAST BODY_TYPE PLUMBING
J 0
(600 475);
DISPLAY 0.872340 (600 475);
PAINT GREEN (600 475);
DISPLAY INVISIBLE (600 475);
FORCEPROP 1 LAST HDL_TAP TRUE
J 0
(925 300);
DISPLAY 0.872340 (925 300);
DISPLAY INVISIBLE (925 300);
FORCEPROP 1 LAST PATH I52
J 0
(598 425);
DISPLAY 0.872340 (598 425);
PAINT GREEN (598 425);
DISPLAY INVISIBLE (598 425);
FORCEADD TAP..1
(600 375);
FORCEPROP 3 LASTPIN (550 375) SIG_NAME M_G_CPU0_SB_DQ<5>
J 0
(560 385);
DISPLAY 0.659574 (560 385);
PAINT MONO (560 385);
DISPLAY INVISIBLE (560 385);
FORCEPROP 1 LASTPIN (550 375) BN 5
J 0
(538 383);
DISPLAY 0.680851 (538 383);
PAINT GREEN (538 383);
FORCEPROP 2 LAST CDS_LIB standard
J 0
(600 375);
PAINT MONO (600 375);
DISPLAY INVISIBLE (600 375);
FORCEPROP 1 LAST BODY_TYPE PLUMBING
J 0
(600 425);
DISPLAY 0.872340 (600 425);
PAINT GREEN (600 425);
DISPLAY INVISIBLE (600 425);
FORCEPROP 1 LAST HDL_TAP TRUE
J 0
(925 250);
DISPLAY 0.872340 (925 250);
DISPLAY INVISIBLE (925 250);
FORCEPROP 1 LAST PATH I53
J 0
(598 375);
DISPLAY 0.872340 (598 375);
PAINT GREEN (598 375);
DISPLAY INVISIBLE (598 375);
FORCEADD TAP..1
(600 325);
FORCEPROP 3 LASTPIN (550 325) SIG_NAME M_G_CPU0_SB_DQ<4>
J 0
(560 335);
DISPLAY 0.659574 (560 335);
PAINT MONO (560 335);
DISPLAY INVISIBLE (560 335);
FORCEPROP 1 LASTPIN (550 325) BN 4
J 0
(538 333);
DISPLAY 0.680851 (538 333);
PAINT GREEN (538 333);
FORCEPROP 2 LAST CDS_LIB standard
J 0
(600 325);
PAINT MONO (600 325);
DISPLAY INVISIBLE (600 325);
FORCEPROP 1 LAST BODY_TYPE PLUMBING
J 0
(600 375);
DISPLAY 0.872340 (600 375);
PAINT GREEN (600 375);
DISPLAY INVISIBLE (600 375);
FORCEPROP 1 LAST HDL_TAP TRUE
J 0
(925 200);
DISPLAY 0.872340 (925 200);
DISPLAY INVISIBLE (925 200);
FORCEPROP 1 LAST PATH I54
J 0
(598 325);
DISPLAY 0.872340 (598 325);
PAINT GREEN (598 325);
DISPLAY INVISIBLE (598 325);
FORCEADD TAP..1
(600 525);
FORCEPROP 3 LASTPIN (550 525) SIG_NAME M_G_CPU0_SB_DQ<8>
J 0
(560 535);
DISPLAY 0.659574 (560 535);
PAINT MONO (560 535);
DISPLAY INVISIBLE (560 535);
FORCEPROP 1 LASTPIN (550 525) BN 8
J 0
(538 533);
DISPLAY 0.680851 (538 533);
PAINT GREEN (538 533);
FORCEPROP 2 LAST CDS_LIB standard
J 0
(600 525);
PAINT MONO (600 525);
DISPLAY INVISIBLE (600 525);
FORCEPROP 1 LAST BODY_TYPE PLUMBING
J 0
(600 575);
DISPLAY 0.872340 (600 575);
PAINT GREEN (600 575);
DISPLAY INVISIBLE (600 575);
FORCEPROP 1 LAST HDL_TAP TRUE
J 0
(925 400);
DISPLAY 0.872340 (925 400);
DISPLAY INVISIBLE (925 400);
FORCEPROP 1 LAST PATH I55
J 0
(598 525);
DISPLAY 0.872340 (598 525);
PAINT GREEN (598 525);
DISPLAY INVISIBLE (598 525);
FORCEADD TAP..1
(600 475);
FORCEPROP 3 LASTPIN (550 475) SIG_NAME M_G_CPU0_SB_DQ<7>
J 0
(560 485);
DISPLAY 0.659574 (560 485);
PAINT MONO (560 485);
DISPLAY INVISIBLE (560 485);
FORCEPROP 1 LASTPIN (550 475) BN 7
J 0
(538 483);
DISPLAY 0.680851 (538 483);
PAINT GREEN (538 483);
FORCEPROP 2 LAST CDS_LIB standard
J 0
(600 475);
PAINT MONO (600 475);
DISPLAY INVISIBLE (600 475);
FORCEPROP 1 LAST BODY_TYPE PLUMBING
J 0
(600 525);
DISPLAY 0.872340 (600 525);
PAINT GREEN (600 525);
DISPLAY INVISIBLE (600 525);
FORCEPROP 1 LAST HDL_TAP TRUE
J 0
(925 350);
DISPLAY 0.872340 (925 350);
DISPLAY INVISIBLE (925 350);
FORCEPROP 1 LAST PATH I56
J 0
(598 475);
DISPLAY 0.872340 (598 475);
PAINT GREEN (598 475);
DISPLAY INVISIBLE (598 475);
FORCEADD TAP..1
(600 575);
FORCEPROP 3 LASTPIN (550 575) SIG_NAME M_G_CPU0_SB_DQ<9>
J 0
(560 585);
DISPLAY 0.659574 (560 585);
PAINT MONO (560 585);
DISPLAY INVISIBLE (560 585);
FORCEPROP 1 LASTPIN (550 575) BN 9
J 0
(538 583);
DISPLAY 0.680851 (538 583);
PAINT GREEN (538 583);
FORCEPROP 2 LAST CDS_LIB standard
J 0
(600 575);
PAINT MONO (600 575);
DISPLAY INVISIBLE (600 575);
FORCEPROP 1 LAST BODY_TYPE PLUMBING
J 0
(600 625);
DISPLAY 0.872340 (600 625);
PAINT GREEN (600 625);
DISPLAY INVISIBLE (600 625);
FORCEPROP 1 LAST HDL_TAP TRUE
J 0
(925 450);
DISPLAY 0.872340 (925 450);
DISPLAY INVISIBLE (925 450);
FORCEPROP 1 LAST PATH I57
J 0
(598 575);
DISPLAY 0.872340 (598 575);
PAINT GREEN (598 575);
DISPLAY INVISIBLE (598 575);
FORCEADD TAP..1
(600 625);
FORCEPROP 3 LASTPIN (550 625) SIG_NAME M_G_CPU0_SB_DQ<10>
J 0
(560 635);
DISPLAY 0.659574 (560 635);
PAINT MONO (560 635);
DISPLAY INVISIBLE (560 635);
FORCEPROP 1 LASTPIN (550 625) BN 10
J 0
(538 633);
DISPLAY 0.680851 (538 633);
PAINT GREEN (538 633);
FORCEPROP 2 LAST CDS_LIB standard
J 0
(600 625);
PAINT MONO (600 625);
DISPLAY INVISIBLE (600 625);
FORCEPROP 1 LAST BODY_TYPE PLUMBING
J 0
(600 675);
DISPLAY 0.872340 (600 675);
PAINT GREEN (600 675);
DISPLAY INVISIBLE (600 675);
FORCEPROP 1 LAST HDL_TAP TRUE
J 0
(925 500);
DISPLAY 0.872340 (925 500);
DISPLAY INVISIBLE (925 500);
FORCEPROP 1 LAST PATH I58
J 0
(598 625);
DISPLAY 0.872340 (598 625);
PAINT GREEN (598 625);
DISPLAY INVISIBLE (598 625);
FORCEADD TAP..1
(600 675);
FORCEPROP 3 LASTPIN (550 675) SIG_NAME M_G_CPU0_SB_DQ<11>
J 0
(560 685);
DISPLAY 0.659574 (560 685);
PAINT MONO (560 685);
DISPLAY INVISIBLE (560 685);
FORCEPROP 1 LASTPIN (550 675) BN 11
J 0
(538 683);
DISPLAY 0.680851 (538 683);
PAINT GREEN (538 683);
FORCEPROP 2 LAST CDS_LIB standard
J 0
(600 675);
PAINT MONO (600 675);
DISPLAY INVISIBLE (600 675);
FORCEPROP 1 LAST BODY_TYPE PLUMBING
J 0
(600 725);
DISPLAY 0.872340 (600 725);
PAINT GREEN (600 725);
DISPLAY INVISIBLE (600 725);
FORCEPROP 1 LAST HDL_TAP TRUE
J 0
(925 550);
DISPLAY 0.872340 (925 550);
DISPLAY INVISIBLE (925 550);
FORCEPROP 1 LAST PATH I59
J 0
(598 675);
DISPLAY 0.872340 (598 675);
PAINT GREEN (598 675);
DISPLAY INVISIBLE (598 675);
FORCEADD OFFPAGE..1
(-1900 825);
FORCEPROP 2 LAST $XR0 95 
J 0
(-2361 825);
DISPLAY 0.638298 (-2361 825);
PAINT MONO (-2361 825);
FORCEPROP 2 LAST CDS_LIB standard
J 0
(-1900 825);
PAINT MONO (-1900 825);
DISPLAY INVISIBLE (-1900 825);
FORCEPROP 1 LAST OFFPAGE TRUE
J 0
(-1575 700);
DISPLAY 0.872340 (-1575 700);
DISPLAY INVISIBLE (-1575 700);
FORCEPROP 1 LAST COMMENT_BODY TRUE
J 0
(-1775 725);
DISPLAY 0.872340 (-1775 725);
PAINT GREEN (-1775 725);
DISPLAY INVISIBLE (-1775 725);
FORCEPROP 2 LAST PATH I6
J 0
(-1850 900);
DISPLAY 1.021277 (-1850 900);
DISPLAY INVISIBLE (-1850 900);
FORCEADD TAP..1
(600 775);
FORCEPROP 3 LASTPIN (550 775) SIG_NAME M_G_CPU0_SB_DQ<13>
J 0
(560 785);
DISPLAY 0.659574 (560 785);
PAINT MONO (560 785);
DISPLAY INVISIBLE (560 785);
FORCEPROP 1 LASTPIN (550 775) BN 13
J 0
(538 783);
DISPLAY 0.680851 (538 783);
PAINT GREEN (538 783);
FORCEPROP 2 LAST CDS_LIB standard
J 0
(600 775);
PAINT MONO (600 775);
DISPLAY INVISIBLE (600 775);
FORCEPROP 1 LAST BODY_TYPE PLUMBING
J 0
(600 825);
DISPLAY 0.872340 (600 825);
PAINT GREEN (600 825);
DISPLAY INVISIBLE (600 825);
FORCEPROP 1 LAST HDL_TAP TRUE
J 0
(925 650);
DISPLAY 0.872340 (925 650);
DISPLAY INVISIBLE (925 650);
FORCEPROP 1 LAST PATH I60
J 0
(598 775);
DISPLAY 0.872340 (598 775);
PAINT GREEN (598 775);
DISPLAY INVISIBLE (598 775);
FORCEADD TAP..1
(600 725);
FORCEPROP 3 LASTPIN (550 725) SIG_NAME M_G_CPU0_SB_DQ<12>
J 0
(560 735);
DISPLAY 0.659574 (560 735);
PAINT MONO (560 735);
DISPLAY INVISIBLE (560 735);
FORCEPROP 1 LASTPIN (550 725) BN 12
J 0
(538 733);
DISPLAY 0.680851 (538 733);
PAINT GREEN (538 733);
FORCEPROP 2 LAST CDS_LIB standard
J 0
(600 725);
PAINT MONO (600 725);
DISPLAY INVISIBLE (600 725);
FORCEPROP 1 LAST BODY_TYPE PLUMBING
J 0
(600 775);
DISPLAY 0.872340 (600 775);
PAINT GREEN (600 775);
DISPLAY INVISIBLE (600 775);
FORCEPROP 1 LAST HDL_TAP TRUE
J 0
(925 600);
DISPLAY 0.872340 (925 600);
DISPLAY INVISIBLE (925 600);
FORCEPROP 1 LAST PATH I61
J 0
(598 725);
DISPLAY 0.872340 (598 725);
PAINT GREEN (598 725);
DISPLAY INVISIBLE (598 725);
FORCEADD TAP..1
(600 825);
FORCEPROP 3 LASTPIN (550 825) SIG_NAME M_G_CPU0_SB_DQ<14>
J 0
(560 835);
DISPLAY 0.659574 (560 835);
PAINT MONO (560 835);
DISPLAY INVISIBLE (560 835);
FORCEPROP 1 LASTPIN (550 825) BN 14
J 0
(538 833);
DISPLAY 0.680851 (538 833);
PAINT GREEN (538 833);
FORCEPROP 2 LAST CDS_LIB standard
J 0
(600 825);
PAINT MONO (600 825);
DISPLAY INVISIBLE (600 825);
FORCEPROP 1 LAST BODY_TYPE PLUMBING
J 0
(600 875);
DISPLAY 0.872340 (600 875);
PAINT GREEN (600 875);
DISPLAY INVISIBLE (600 875);
FORCEPROP 1 LAST HDL_TAP TRUE
J 0
(925 700);
DISPLAY 0.872340 (925 700);
DISPLAY INVISIBLE (925 700);
FORCEPROP 1 LAST PATH I62
J 0
(598 825);
DISPLAY 0.872340 (598 825);
PAINT GREEN (598 825);
DISPLAY INVISIBLE (598 825);
FORCEADD TAP..1
(600 875);
FORCEPROP 3 LASTPIN (550 875) SIG_NAME M_G_CPU0_SB_DQ<15>
J 0
(560 885);
DISPLAY 0.659574 (560 885);
PAINT MONO (560 885);
DISPLAY INVISIBLE (560 885);
FORCEPROP 1 LASTPIN (550 875) BN 15
J 0
(538 883);
DISPLAY 0.680851 (538 883);
PAINT GREEN (538 883);
FORCEPROP 2 LAST CDS_LIB standard
J 0
(600 875);
PAINT MONO (600 875);
DISPLAY INVISIBLE (600 875);
FORCEPROP 1 LAST BODY_TYPE PLUMBING
J 0
(600 925);
DISPLAY 0.872340 (600 925);
PAINT GREEN (600 925);
DISPLAY INVISIBLE (600 925);
FORCEPROP 1 LAST HDL_TAP TRUE
J 0
(925 750);
DISPLAY 0.872340 (925 750);
DISPLAY INVISIBLE (925 750);
FORCEPROP 1 LAST PATH I63
J 0
(598 875);
DISPLAY 0.872340 (598 875);
PAINT GREEN (598 875);
DISPLAY INVISIBLE (598 875);
FORCEADD TAP..1
(600 925);
FORCEPROP 3 LASTPIN (550 925) SIG_NAME M_G_CPU0_SB_DQ<16>
J 0
(560 935);
DISPLAY 0.659574 (560 935);
PAINT MONO (560 935);
DISPLAY INVISIBLE (560 935);
FORCEPROP 1 LASTPIN (550 925) BN 16
J 0
(538 933);
DISPLAY 0.680851 (538 933);
PAINT GREEN (538 933);
FORCEPROP 2 LAST CDS_LIB standard
J 0
(600 925);
PAINT MONO (600 925);
DISPLAY INVISIBLE (600 925);
FORCEPROP 1 LAST BODY_TYPE PLUMBING
J 0
(600 975);
DISPLAY 0.872340 (600 975);
PAINT GREEN (600 975);
DISPLAY INVISIBLE (600 975);
FORCEPROP 1 LAST HDL_TAP TRUE
J 0
(925 800);
DISPLAY 0.872340 (925 800);
DISPLAY INVISIBLE (925 800);
FORCEPROP 1 LAST PATH I64
J 0
(598 925);
DISPLAY 0.872340 (598 925);
PAINT GREEN (598 925);
DISPLAY INVISIBLE (598 925);
FORCEADD TAP..1
(600 1075);
FORCEPROP 3 LASTPIN (550 1075) SIG_NAME M_G_CPU0_SB_DQ<19>
J 0
(560 1085);
DISPLAY 0.659574 (560 1085);
PAINT MONO (560 1085);
DISPLAY INVISIBLE (560 1085);
FORCEPROP 1 LASTPIN (550 1075) BN 19
J 0
(538 1083);
DISPLAY 0.680851 (538 1083);
PAINT GREEN (538 1083);
FORCEPROP 2 LAST CDS_LIB standard
J 0
(600 1075);
PAINT MONO (600 1075);
DISPLAY INVISIBLE (600 1075);
FORCEPROP 1 LAST BODY_TYPE PLUMBING
J 0
(600 1125);
DISPLAY 0.872340 (600 1125);
PAINT GREEN (600 1125);
DISPLAY INVISIBLE (600 1125);
FORCEPROP 1 LAST HDL_TAP TRUE
J 0
(925 950);
DISPLAY 0.872340 (925 950);
DISPLAY INVISIBLE (925 950);
FORCEPROP 1 LAST PATH I65
J 0
(598 1075);
DISPLAY 0.872340 (598 1075);
PAINT GREEN (598 1075);
DISPLAY INVISIBLE (598 1075);
FORCEADD TAP..1
(600 1025);
FORCEPROP 3 LASTPIN (550 1025) SIG_NAME M_G_CPU0_SB_DQ<18>
J 0
(560 1035);
DISPLAY 0.659574 (560 1035);
PAINT MONO (560 1035);
DISPLAY INVISIBLE (560 1035);
FORCEPROP 1 LASTPIN (550 1025) BN 18
J 0
(538 1033);
DISPLAY 0.680851 (538 1033);
PAINT GREEN (538 1033);
FORCEPROP 2 LAST CDS_LIB standard
J 0
(600 1025);
PAINT MONO (600 1025);
DISPLAY INVISIBLE (600 1025);
FORCEPROP 1 LAST BODY_TYPE PLUMBING
J 0
(600 1075);
DISPLAY 0.872340 (600 1075);
PAINT GREEN (600 1075);
DISPLAY INVISIBLE (600 1075);
FORCEPROP 1 LAST HDL_TAP TRUE
J 0
(925 900);
DISPLAY 0.872340 (925 900);
DISPLAY INVISIBLE (925 900);
FORCEPROP 1 LAST PATH I66
J 0
(598 1025);
DISPLAY 0.872340 (598 1025);
PAINT GREEN (598 1025);
DISPLAY INVISIBLE (598 1025);
FORCEADD TAP..1
(600 975);
FORCEPROP 3 LASTPIN (550 975) SIG_NAME M_G_CPU0_SB_DQ<17>
J 0
(560 985);
DISPLAY 0.659574 (560 985);
PAINT MONO (560 985);
DISPLAY INVISIBLE (560 985);
FORCEPROP 1 LASTPIN (550 975) BN 17
J 0
(538 983);
DISPLAY 0.680851 (538 983);
PAINT GREEN (538 983);
FORCEPROP 2 LAST CDS_LIB standard
J 0
(600 975);
PAINT MONO (600 975);
DISPLAY INVISIBLE (600 975);
FORCEPROP 1 LAST BODY_TYPE PLUMBING
J 0
(600 1025);
DISPLAY 0.872340 (600 1025);
PAINT GREEN (600 1025);
DISPLAY INVISIBLE (600 1025);
FORCEPROP 1 LAST HDL_TAP TRUE
J 0
(925 850);
DISPLAY 0.872340 (925 850);
DISPLAY INVISIBLE (925 850);
FORCEPROP 1 LAST PATH I67
J 0
(598 975);
DISPLAY 0.872340 (598 975);
PAINT GREEN (598 975);
DISPLAY INVISIBLE (598 975);
FORCEADD TAP..1
(600 1175);
FORCEPROP 3 LASTPIN (550 1175) SIG_NAME M_G_CPU0_SB_DQ<21>
J 0
(560 1185);
DISPLAY 0.659574 (560 1185);
PAINT MONO (560 1185);
DISPLAY INVISIBLE (560 1185);
FORCEPROP 1 LASTPIN (550 1175) BN 21
J 0
(538 1183);
DISPLAY 0.680851 (538 1183);
PAINT GREEN (538 1183);
FORCEPROP 2 LAST CDS_LIB standard
J 0
(600 1175);
PAINT MONO (600 1175);
DISPLAY INVISIBLE (600 1175);
FORCEPROP 1 LAST BODY_TYPE PLUMBING
J 0
(600 1225);
DISPLAY 0.872340 (600 1225);
PAINT GREEN (600 1225);
DISPLAY INVISIBLE (600 1225);
FORCEPROP 1 LAST HDL_TAP TRUE
J 0
(925 1050);
DISPLAY 0.872340 (925 1050);
DISPLAY INVISIBLE (925 1050);
FORCEPROP 1 LAST PATH I68
J 0
(598 1175);
DISPLAY 0.872340 (598 1175);
PAINT GREEN (598 1175);
DISPLAY INVISIBLE (598 1175);
FORCEADD TAP..1
(600 1125);
FORCEPROP 3 LASTPIN (550 1125) SIG_NAME M_G_CPU0_SB_DQ<20>
J 0
(560 1135);
DISPLAY 0.659574 (560 1135);
PAINT MONO (560 1135);
DISPLAY INVISIBLE (560 1135);
FORCEPROP 1 LASTPIN (550 1125) BN 20
J 0
(538 1133);
DISPLAY 0.680851 (538 1133);
PAINT GREEN (538 1133);
FORCEPROP 2 LAST CDS_LIB standard
J 0
(600 1125);
PAINT MONO (600 1125);
DISPLAY INVISIBLE (600 1125);
FORCEPROP 1 LAST BODY_TYPE PLUMBING
J 0
(600 1175);
DISPLAY 0.872340 (600 1175);
PAINT GREEN (600 1175);
DISPLAY INVISIBLE (600 1175);
FORCEPROP 1 LAST HDL_TAP TRUE
J 0
(925 1000);
DISPLAY 0.872340 (925 1000);
DISPLAY INVISIBLE (925 1000);
FORCEPROP 1 LAST PATH I69
J 0
(598 1125);
DISPLAY 0.872340 (598 1125);
PAINT GREEN (598 1125);
DISPLAY INVISIBLE (598 1125);
FORCEADD OFFPAGE..1
(-1900 775);
FORCEPROP 2 LAST $XR7 97 
J 0
(-2272 811);
DISPLAY 0.638298 (-2272 811);
PAINT MONO (-2272 811);
FORCEPROP 2 LAST $XR6 96 
J 0
(-2182 811);
DISPLAY 0.638298 (-2182 811);
PAINT MONO (-2182 811);
FORCEPROP 2 LAST $XR5 94 
J 0
(-2362 739);
DISPLAY 0.638298 (-2362 739);
PAINT MONO (-2362 739);
FORCEPROP 2 LAST $XR4 93 
J 0
(-2272 739);
DISPLAY 0.638298 (-2272 739);
PAINT MONO (-2272 739);
FORCEPROP 2 LAST $XR3 92 
J 0
(-2182 739);
DISPLAY 0.638298 (-2182 739);
PAINT MONO (-2182 739);
FORCEPROP 2 LAST $XR2 91 
J 0
(-2362 775);
DISPLAY 0.638298 (-2362 775);
PAINT MONO (-2362 775);
FORCEPROP 2 LAST $XR1 90 
J 0
(-2272 775);
DISPLAY 0.638298 (-2272 775);
PAINT MONO (-2272 775);
FORCEPROP 2 LAST $XR0 229 
J 0
(-2182 775);
DISPLAY 0.638298 (-2182 775);
PAINT MONO (-2182 775);
FORCEPROP 2 LAST CDS_LIB standard
J 0
(-1900 775);
PAINT MONO (-1900 775);
DISPLAY INVISIBLE (-1900 775);
FORCEPROP 1 LAST OFFPAGE TRUE
J 0
(-1575 650);
DISPLAY 0.872340 (-1575 650);
DISPLAY INVISIBLE (-1575 650);
FORCEPROP 1 LAST COMMENT_BODY TRUE
J 0
(-1775 675);
DISPLAY 0.872340 (-1775 675);
PAINT GREEN (-1775 675);
DISPLAY INVISIBLE (-1775 675);
FORCEPROP 2 LAST PATH I7
J 0
(-1850 850);
DISPLAY 1.021277 (-1850 850);
DISPLAY INVISIBLE (-1850 850);
FORCEADD TAP..1
(600 1325);
FORCEPROP 3 LASTPIN (550 1325) SIG_NAME M_G_CPU0_SB_DQ<24>
J 0
(560 1335);
DISPLAY 0.659574 (560 1335);
PAINT MONO (560 1335);
DISPLAY INVISIBLE (560 1335);
FORCEPROP 1 LASTPIN (550 1325) BN 24
J 0
(538 1333);
DISPLAY 0.680851 (538 1333);
PAINT GREEN (538 1333);
FORCEPROP 2 LAST CDS_LIB standard
J 0
(600 1325);
DISPLAY INVISIBLE (600 1325);
FORCEPROP 1 LAST BODY_TYPE PLUMBING
J 0
(600 1375);
DISPLAY 0.872340 (600 1375);
PAINT GREEN (600 1375);
DISPLAY INVISIBLE (600 1375);
FORCEPROP 1 LAST HDL_TAP TRUE
J 0
(925 1200);
DISPLAY 0.872340 (925 1200);
DISPLAY INVISIBLE (925 1200);
FORCEPROP 1 LAST PATH I70
J 0
(598 1325);
DISPLAY 0.872340 (598 1325);
PAINT GREEN (598 1325);
DISPLAY INVISIBLE (598 1325);
FORCEADD TAP..1
(600 1275);
FORCEPROP 3 LASTPIN (550 1275) SIG_NAME M_G_CPU0_SB_DQ<23>
J 0
(560 1285);
DISPLAY 0.659574 (560 1285);
PAINT MONO (560 1285);
DISPLAY INVISIBLE (560 1285);
FORCEPROP 1 LASTPIN (550 1275) BN 23
J 0
(538 1283);
DISPLAY 0.680851 (538 1283);
PAINT GREEN (538 1283);
FORCEPROP 2 LAST CDS_LIB standard
J 0
(600 1275);
DISPLAY INVISIBLE (600 1275);
FORCEPROP 1 LAST BODY_TYPE PLUMBING
J 0
(600 1325);
DISPLAY 0.872340 (600 1325);
PAINT GREEN (600 1325);
DISPLAY INVISIBLE (600 1325);
FORCEPROP 1 LAST HDL_TAP TRUE
J 0
(925 1150);
DISPLAY 0.872340 (925 1150);
DISPLAY INVISIBLE (925 1150);
FORCEPROP 1 LAST PATH I71
J 0
(598 1275);
DISPLAY 0.872340 (598 1275);
PAINT GREEN (598 1275);
DISPLAY INVISIBLE (598 1275);
FORCEADD TAP..1
(600 1225);
FORCEPROP 3 LASTPIN (550 1225) SIG_NAME M_G_CPU0_SB_DQ<22>
J 0
(560 1235);
DISPLAY 0.659574 (560 1235);
PAINT MONO (560 1235);
DISPLAY INVISIBLE (560 1235);
FORCEPROP 1 LASTPIN (550 1225) BN 22
J 0
(538 1233);
DISPLAY 0.680851 (538 1233);
PAINT GREEN (538 1233);
FORCEPROP 2 LAST CDS_LIB standard
J 0
(600 1225);
DISPLAY INVISIBLE (600 1225);
FORCEPROP 1 LAST BODY_TYPE PLUMBING
J 0
(600 1275);
DISPLAY 0.872340 (600 1275);
PAINT GREEN (600 1275);
DISPLAY INVISIBLE (600 1275);
FORCEPROP 1 LAST HDL_TAP TRUE
J 0
(925 1100);
DISPLAY 0.872340 (925 1100);
DISPLAY INVISIBLE (925 1100);
FORCEPROP 1 LAST PATH I72
J 0
(598 1225);
DISPLAY 0.872340 (598 1225);
PAINT GREEN (598 1225);
DISPLAY INVISIBLE (598 1225);
FORCEADD TAP..1
(600 1375);
FORCEPROP 3 LASTPIN (550 1375) SIG_NAME M_G_CPU0_SB_DQ<25>
J 0
(560 1385);
DISPLAY 0.659574 (560 1385);
PAINT MONO (560 1385);
DISPLAY INVISIBLE (560 1385);
FORCEPROP 1 LASTPIN (550 1375) BN 25
J 0
(538 1383);
DISPLAY 0.680851 (538 1383);
PAINT GREEN (538 1383);
FORCEPROP 2 LAST CDS_LIB standard
J 0
(600 1375);
DISPLAY INVISIBLE (600 1375);
FORCEPROP 1 LAST BODY_TYPE PLUMBING
J 0
(600 1425);
DISPLAY 0.872340 (600 1425);
PAINT GREEN (600 1425);
DISPLAY INVISIBLE (600 1425);
FORCEPROP 1 LAST HDL_TAP TRUE
J 0
(925 1250);
DISPLAY 0.872340 (925 1250);
DISPLAY INVISIBLE (925 1250);
FORCEPROP 1 LAST PATH I73
J 0
(598 1375);
DISPLAY 0.872340 (598 1375);
PAINT GREEN (598 1375);
DISPLAY INVISIBLE (598 1375);
FORCEADD TAP..1
(600 1425);
FORCEPROP 3 LASTPIN (550 1425) SIG_NAME M_G_CPU0_SB_DQ<26>
J 0
(560 1435);
DISPLAY 0.659574 (560 1435);
PAINT MONO (560 1435);
DISPLAY INVISIBLE (560 1435);
FORCEPROP 1 LASTPIN (550 1425) BN 26
J 0
(538 1433);
DISPLAY 0.680851 (538 1433);
PAINT GREEN (538 1433);
FORCEPROP 2 LAST CDS_LIB standard
J 0
(600 1425);
DISPLAY INVISIBLE (600 1425);
FORCEPROP 1 LAST BODY_TYPE PLUMBING
J 0
(600 1475);
DISPLAY 0.872340 (600 1475);
PAINT GREEN (600 1475);
DISPLAY INVISIBLE (600 1475);
FORCEPROP 1 LAST HDL_TAP TRUE
J 0
(925 1300);
DISPLAY 0.872340 (925 1300);
DISPLAY INVISIBLE (925 1300);
FORCEPROP 1 LAST PATH I74
J 0
(598 1425);
DISPLAY 0.872340 (598 1425);
PAINT GREEN (598 1425);
DISPLAY INVISIBLE (598 1425);
FORCEADD TAP..1
(600 1575);
FORCEPROP 3 LASTPIN (550 1575) SIG_NAME M_G_CPU0_SB_DQ<29>
J 0
(560 1585);
DISPLAY 0.659574 (560 1585);
PAINT MONO (560 1585);
DISPLAY INVISIBLE (560 1585);
FORCEPROP 1 LASTPIN (550 1575) BN 29
J 0
(538 1583);
DISPLAY 0.680851 (538 1583);
PAINT GREEN (538 1583);
FORCEPROP 2 LAST CDS_LIB standard
J 0
(600 1575);
DISPLAY INVISIBLE (600 1575);
FORCEPROP 1 LAST BODY_TYPE PLUMBING
J 0
(600 1625);
DISPLAY 0.872340 (600 1625);
PAINT GREEN (600 1625);
DISPLAY INVISIBLE (600 1625);
FORCEPROP 1 LAST HDL_TAP TRUE
J 0
(925 1450);
DISPLAY 0.872340 (925 1450);
DISPLAY INVISIBLE (925 1450);
FORCEPROP 1 LAST PATH I75
J 0
(598 1575);
DISPLAY 0.872340 (598 1575);
PAINT GREEN (598 1575);
DISPLAY INVISIBLE (598 1575);
FORCEADD TAP..1
(600 1525);
FORCEPROP 3 LASTPIN (550 1525) SIG_NAME M_G_CPU0_SB_DQ<28>
J 0
(560 1535);
DISPLAY 0.659574 (560 1535);
PAINT MONO (560 1535);
DISPLAY INVISIBLE (560 1535);
FORCEPROP 1 LASTPIN (550 1525) BN 28
J 0
(538 1533);
DISPLAY 0.680851 (538 1533);
PAINT GREEN (538 1533);
FORCEPROP 2 LAST CDS_LIB standard
J 0
(600 1525);
DISPLAY INVISIBLE (600 1525);
FORCEPROP 1 LAST BODY_TYPE PLUMBING
J 0
(600 1575);
DISPLAY 0.872340 (600 1575);
PAINT GREEN (600 1575);
DISPLAY INVISIBLE (600 1575);
FORCEPROP 1 LAST HDL_TAP TRUE
J 0
(925 1400);
DISPLAY 0.872340 (925 1400);
DISPLAY INVISIBLE (925 1400);
FORCEPROP 1 LAST PATH I76
J 0
(598 1525);
DISPLAY 0.872340 (598 1525);
PAINT GREEN (598 1525);
DISPLAY INVISIBLE (598 1525);
FORCEADD TAP..1
(600 1475);
FORCEPROP 3 LASTPIN (550 1475) SIG_NAME M_G_CPU0_SB_DQ<27>
J 0
(560 1485);
DISPLAY 0.659574 (560 1485);
PAINT MONO (560 1485);
DISPLAY INVISIBLE (560 1485);
FORCEPROP 1 LASTPIN (550 1475) BN 27
J 0
(538 1483);
DISPLAY 0.680851 (538 1483);
PAINT GREEN (538 1483);
FORCEPROP 2 LAST CDS_LIB standard
J 0
(600 1475);
DISPLAY INVISIBLE (600 1475);
FORCEPROP 1 LAST BODY_TYPE PLUMBING
J 0
(600 1525);
DISPLAY 0.872340 (600 1525);
PAINT GREEN (600 1525);
DISPLAY INVISIBLE (600 1525);
FORCEPROP 1 LAST HDL_TAP TRUE
J 0
(925 1350);
DISPLAY 0.872340 (925 1350);
DISPLAY INVISIBLE (925 1350);
FORCEPROP 1 LAST PATH I77
J 0
(598 1475);
DISPLAY 0.872340 (598 1475);
PAINT GREEN (598 1475);
DISPLAY INVISIBLE (598 1475);
FORCEADD TAP..1
(600 1625);
FORCEPROP 3 LASTPIN (550 1625) SIG_NAME M_G_CPU0_SB_DQ<30>
J 0
(560 1635);
DISPLAY 0.659574 (560 1635);
PAINT MONO (560 1635);
DISPLAY INVISIBLE (560 1635);
FORCEPROP 1 LASTPIN (550 1625) BN 30
J 0
(538 1633);
DISPLAY 0.680851 (538 1633);
PAINT GREEN (538 1633);
FORCEPROP 2 LAST CDS_LIB standard
J 0
(600 1625);
DISPLAY INVISIBLE (600 1625);
FORCEPROP 1 LAST BODY_TYPE PLUMBING
J 0
(600 1675);
DISPLAY 0.872340 (600 1675);
PAINT GREEN (600 1675);
DISPLAY INVISIBLE (600 1675);
FORCEPROP 1 LAST HDL_TAP TRUE
J 0
(925 1500);
DISPLAY 0.872340 (925 1500);
DISPLAY INVISIBLE (925 1500);
FORCEPROP 1 LAST PATH I78
J 0
(598 1625);
DISPLAY 0.872340 (598 1625);
PAINT GREEN (598 1625);
DISPLAY INVISIBLE (598 1625);
FORCEADD TAP..1
(600 1675);
FORCEPROP 3 LASTPIN (550 1675) SIG_NAME M_G_CPU0_SB_DQ<31>
J 0
(560 1685);
DISPLAY 0.659574 (560 1685);
PAINT MONO (560 1685);
DISPLAY INVISIBLE (560 1685);
FORCEPROP 1 LASTPIN (550 1675) BN 31
J 0
(538 1683);
DISPLAY 0.680851 (538 1683);
PAINT GREEN (538 1683);
FORCEPROP 2 LAST CDS_LIB standard
J 0
(600 1675);
DISPLAY INVISIBLE (600 1675);
FORCEPROP 1 LAST BODY_TYPE PLUMBING
J 0
(600 1725);
DISPLAY 0.872340 (600 1725);
PAINT GREEN (600 1725);
DISPLAY INVISIBLE (600 1725);
FORCEPROP 1 LAST HDL_TAP TRUE
J 0
(925 1550);
DISPLAY 0.872340 (925 1550);
DISPLAY INVISIBLE (925 1550);
FORCEPROP 1 LAST PATH I79
J 0
(598 1675);
DISPLAY 0.872340 (598 1675);
PAINT GREEN (598 1675);
DISPLAY INVISIBLE (598 1675);
FORCEADD OFFPAGE..1
(-1975 975);
FORCEPROP 2 LAST $XR1 94 
J 0
(-2286 975);
DISPLAY 0.638298 (-2286 975);
PAINT MONO (-2286 975);
FORCEPROP 2 LAST $XR0 26 
J 0
(-2196 975);
DISPLAY 0.638298 (-2196 975);
PAINT MONO (-2196 975);
FORCEPROP 2 LAST CDS_LIB standard
J 0
(-1975 975);
PAINT MONO (-1975 975);
DISPLAY INVISIBLE (-1975 975);
FORCEPROP 1 LAST OFFPAGE TRUE
J 0
(-1650 850);
DISPLAY 0.872340 (-1650 850);
DISPLAY INVISIBLE (-1650 850);
FORCEPROP 1 LAST COMMENT_BODY TRUE
J 0
(-1850 875);
DISPLAY 0.872340 (-1850 875);
PAINT GREEN (-1850 875);
DISPLAY INVISIBLE (-1850 875);
FORCEPROP 2 LAST PATH I8
J 0
(-1925 1050);
DISPLAY 1.021277 (-1925 1050);
DISPLAY INVISIBLE (-1925 1050);
FORCEADD TAP..1
(600 1775);
FORCEPROP 3 LASTPIN (550 1775) SIG_NAME M_G_CPU0_SA_DQ<0>
J 0
(560 1785);
DISPLAY 0.659574 (560 1785);
PAINT MONO (560 1785);
DISPLAY INVISIBLE (560 1785);
FORCEPROP 1 LASTPIN (550 1775) BN 0
J 0
(538 1783);
DISPLAY 0.680851 (538 1783);
PAINT GREEN (538 1783);
FORCEPROP 2 LAST CDS_LIB standard
J 0
(600 1775);
PAINT MONO (600 1775);
DISPLAY INVISIBLE (600 1775);
FORCEPROP 1 LAST BODY_TYPE PLUMBING
J 0
(600 1825);
DISPLAY 0.872340 (600 1825);
PAINT GREEN (600 1825);
DISPLAY INVISIBLE (600 1825);
FORCEPROP 1 LAST HDL_TAP TRUE
J 0
(925 1650);
DISPLAY 0.872340 (925 1650);
DISPLAY INVISIBLE (925 1650);
FORCEPROP 1 LAST PATH I80
J 0
(598 1775);
DISPLAY 0.872340 (598 1775);
PAINT GREEN (598 1775);
DISPLAY INVISIBLE (598 1775);
FORCEADD TAP..1
(600 1825);
FORCEPROP 3 LASTPIN (550 1825) SIG_NAME M_G_CPU0_SA_DQ<1>
J 0
(560 1835);
DISPLAY 0.659574 (560 1835);
PAINT MONO (560 1835);
DISPLAY INVISIBLE (560 1835);
FORCEPROP 1 LASTPIN (550 1825) BN 1
J 0
(538 1833);
DISPLAY 0.680851 (538 1833);
PAINT GREEN (538 1833);
FORCEPROP 2 LAST CDS_LIB standard
J 0
(600 1825);
PAINT MONO (600 1825);
DISPLAY INVISIBLE (600 1825);
FORCEPROP 1 LAST BODY_TYPE PLUMBING
J 0
(600 1875);
DISPLAY 0.872340 (600 1875);
PAINT GREEN (600 1875);
DISPLAY INVISIBLE (600 1875);
FORCEPROP 1 LAST HDL_TAP TRUE
J 0
(925 1700);
DISPLAY 0.872340 (925 1700);
DISPLAY INVISIBLE (925 1700);
FORCEPROP 1 LAST PATH I81
J 0
(598 1825);
DISPLAY 0.872340 (598 1825);
PAINT GREEN (598 1825);
DISPLAY INVISIBLE (598 1825);
FORCEADD TAP..1
(600 1925);
FORCEPROP 3 LASTPIN (550 1925) SIG_NAME M_G_CPU0_SA_DQ<3>
J 0
(560 1935);
DISPLAY 0.659574 (560 1935);
PAINT MONO (560 1935);
DISPLAY INVISIBLE (560 1935);
FORCEPROP 1 LASTPIN (550 1925) BN 3
J 0
(538 1933);
DISPLAY 0.680851 (538 1933);
PAINT GREEN (538 1933);
FORCEPROP 2 LAST CDS_LIB standard
J 0
(600 1925);
PAINT MONO (600 1925);
DISPLAY INVISIBLE (600 1925);
FORCEPROP 1 LAST BODY_TYPE PLUMBING
J 0
(600 1975);
DISPLAY 0.872340 (600 1975);
PAINT GREEN (600 1975);
DISPLAY INVISIBLE (600 1975);
FORCEPROP 1 LAST HDL_TAP TRUE
J 0
(925 1800);
DISPLAY 0.872340 (925 1800);
DISPLAY INVISIBLE (925 1800);
FORCEPROP 1 LAST PATH I82
J 0
(598 1925);
DISPLAY 0.872340 (598 1925);
PAINT GREEN (598 1925);
DISPLAY INVISIBLE (598 1925);
FORCEADD TAP..1
(600 1875);
FORCEPROP 3 LASTPIN (550 1875) SIG_NAME M_G_CPU0_SA_DQ<2>
J 0
(560 1885);
DISPLAY 0.659574 (560 1885);
PAINT MONO (560 1885);
DISPLAY INVISIBLE (560 1885);
FORCEPROP 1 LASTPIN (550 1875) BN 2
J 0
(538 1883);
DISPLAY 0.680851 (538 1883);
PAINT GREEN (538 1883);
FORCEPROP 2 LAST CDS_LIB standard
J 0
(600 1875);
PAINT MONO (600 1875);
DISPLAY INVISIBLE (600 1875);
FORCEPROP 1 LAST BODY_TYPE PLUMBING
J 0
(600 1925);
DISPLAY 0.872340 (600 1925);
PAINT GREEN (600 1925);
DISPLAY INVISIBLE (600 1925);
FORCEPROP 1 LAST HDL_TAP TRUE
J 0
(925 1750);
DISPLAY 0.872340 (925 1750);
DISPLAY INVISIBLE (925 1750);
FORCEPROP 1 LAST PATH I83
J 0
(598 1875);
DISPLAY 0.872340 (598 1875);
PAINT GREEN (598 1875);
DISPLAY INVISIBLE (598 1875);
FORCEADD TAP..1
(600 1975);
FORCEPROP 3 LASTPIN (550 1975) SIG_NAME M_G_CPU0_SA_DQ<4>
J 0
(560 1985);
DISPLAY 0.659574 (560 1985);
PAINT MONO (560 1985);
DISPLAY INVISIBLE (560 1985);
FORCEPROP 1 LASTPIN (550 1975) BN 4
J 0
(538 1983);
DISPLAY 0.680851 (538 1983);
PAINT GREEN (538 1983);
FORCEPROP 2 LAST CDS_LIB standard
J 0
(600 1975);
PAINT MONO (600 1975);
DISPLAY INVISIBLE (600 1975);
FORCEPROP 1 LAST BODY_TYPE PLUMBING
J 0
(600 2025);
DISPLAY 0.872340 (600 2025);
PAINT GREEN (600 2025);
DISPLAY INVISIBLE (600 2025);
FORCEPROP 1 LAST HDL_TAP TRUE
J 0
(925 1850);
DISPLAY 0.872340 (925 1850);
DISPLAY INVISIBLE (925 1850);
FORCEPROP 1 LAST PATH I84
J 0
(598 1975);
DISPLAY 0.872340 (598 1975);
PAINT GREEN (598 1975);
DISPLAY INVISIBLE (598 1975);
FORCEADD TAP..1
(600 2025);
FORCEPROP 3 LASTPIN (550 2025) SIG_NAME M_G_CPU0_SA_DQ<5>
J 0
(560 2035);
DISPLAY 0.659574 (560 2035);
PAINT MONO (560 2035);
DISPLAY INVISIBLE (560 2035);
FORCEPROP 1 LASTPIN (550 2025) BN 5
J 0
(538 2033);
DISPLAY 0.680851 (538 2033);
PAINT GREEN (538 2033);
FORCEPROP 2 LAST CDS_LIB standard
J 0
(600 2025);
PAINT MONO (600 2025);
DISPLAY INVISIBLE (600 2025);
FORCEPROP 1 LAST BODY_TYPE PLUMBING
J 0
(600 2075);
DISPLAY 0.872340 (600 2075);
PAINT GREEN (600 2075);
DISPLAY INVISIBLE (600 2075);
FORCEPROP 1 LAST HDL_TAP TRUE
J 0
(925 1900);
DISPLAY 0.872340 (925 1900);
DISPLAY INVISIBLE (925 1900);
FORCEPROP 1 LAST PATH I85
J 0
(598 2025);
DISPLAY 0.872340 (598 2025);
PAINT GREEN (598 2025);
DISPLAY INVISIBLE (598 2025);
FORCEADD TAP..1
(600 2075);
FORCEPROP 3 LASTPIN (550 2075) SIG_NAME M_G_CPU0_SA_DQ<6>
J 0
(560 2085);
DISPLAY 0.659574 (560 2085);
PAINT MONO (560 2085);
DISPLAY INVISIBLE (560 2085);
FORCEPROP 1 LASTPIN (550 2075) BN 6
J 0
(538 2083);
DISPLAY 0.680851 (538 2083);
PAINT GREEN (538 2083);
FORCEPROP 2 LAST CDS_LIB standard
J 0
(600 2075);
PAINT MONO (600 2075);
DISPLAY INVISIBLE (600 2075);
FORCEPROP 1 LAST BODY_TYPE PLUMBING
J 0
(600 2125);
DISPLAY 0.872340 (600 2125);
PAINT GREEN (600 2125);
DISPLAY INVISIBLE (600 2125);
FORCEPROP 1 LAST HDL_TAP TRUE
J 0
(925 1950);
DISPLAY 0.872340 (925 1950);
DISPLAY INVISIBLE (925 1950);
FORCEPROP 1 LAST PATH I86
J 0
(598 2075);
DISPLAY 0.872340 (598 2075);
PAINT GREEN (598 2075);
DISPLAY INVISIBLE (598 2075);
FORCEADD TAP..1
(600 2125);
FORCEPROP 3 LASTPIN (550 2125) SIG_NAME M_G_CPU0_SA_DQ<7>
J 0
(560 2135);
DISPLAY 0.659574 (560 2135);
PAINT MONO (560 2135);
DISPLAY INVISIBLE (560 2135);
FORCEPROP 1 LASTPIN (550 2125) BN 7
J 0
(538 2133);
DISPLAY 0.680851 (538 2133);
PAINT GREEN (538 2133);
FORCEPROP 2 LAST CDS_LIB standard
J 0
(600 2125);
PAINT MONO (600 2125);
DISPLAY INVISIBLE (600 2125);
FORCEPROP 1 LAST BODY_TYPE PLUMBING
J 0
(600 2175);
DISPLAY 0.872340 (600 2175);
PAINT GREEN (600 2175);
DISPLAY INVISIBLE (600 2175);
FORCEPROP 1 LAST HDL_TAP TRUE
J 0
(925 2000);
DISPLAY 0.872340 (925 2000);
DISPLAY INVISIBLE (925 2000);
FORCEPROP 1 LAST PATH I87
J 0
(598 2125);
DISPLAY 0.872340 (598 2125);
PAINT GREEN (598 2125);
DISPLAY INVISIBLE (598 2125);
FORCEADD TAP..1
(600 2175);
FORCEPROP 3 LASTPIN (550 2175) SIG_NAME M_G_CPU0_SA_DQ<8>
J 0
(560 2185);
DISPLAY 0.659574 (560 2185);
PAINT MONO (560 2185);
DISPLAY INVISIBLE (560 2185);
FORCEPROP 1 LASTPIN (550 2175) BN 8
J 0
(538 2183);
DISPLAY 0.680851 (538 2183);
PAINT GREEN (538 2183);
FORCEPROP 2 LAST CDS_LIB standard
J 0
(600 2175);
PAINT MONO (600 2175);
DISPLAY INVISIBLE (600 2175);
FORCEPROP 1 LAST BODY_TYPE PLUMBING
J 0
(600 2225);
DISPLAY 0.872340 (600 2225);
PAINT GREEN (600 2225);
DISPLAY INVISIBLE (600 2225);
FORCEPROP 1 LAST HDL_TAP TRUE
J 0
(925 2050);
DISPLAY 0.872340 (925 2050);
DISPLAY INVISIBLE (925 2050);
FORCEPROP 1 LAST PATH I88
J 0
(598 2175);
DISPLAY 0.872340 (598 2175);
PAINT GREEN (598 2175);
DISPLAY INVISIBLE (598 2175);
FORCEADD TAP..1
(600 2225);
FORCEPROP 3 LASTPIN (550 2225) SIG_NAME M_G_CPU0_SA_DQ<9>
J 0
(560 2235);
DISPLAY 0.659574 (560 2235);
PAINT MONO (560 2235);
DISPLAY INVISIBLE (560 2235);
FORCEPROP 1 LASTPIN (550 2225) BN 9
J 0
(538 2233);
DISPLAY 0.680851 (538 2233);
PAINT GREEN (538 2233);
FORCEPROP 2 LAST CDS_LIB standard
J 0
(600 2225);
PAINT MONO (600 2225);
DISPLAY INVISIBLE (600 2225);
FORCEPROP 1 LAST BODY_TYPE PLUMBING
J 0
(600 2275);
DISPLAY 0.872340 (600 2275);
PAINT GREEN (600 2275);
DISPLAY INVISIBLE (600 2275);
FORCEPROP 1 LAST HDL_TAP TRUE
J 0
(925 2100);
DISPLAY 0.872340 (925 2100);
DISPLAY INVISIBLE (925 2100);
FORCEPROP 1 LAST PATH I89
J 0
(598 2225);
DISPLAY 0.872340 (598 2225);
PAINT GREEN (598 2225);
DISPLAY INVISIBLE (598 2225);
FORCEADD OFFPAGE..1
(-1975 1075);
FORCEPROP 2 LAST $XR3 97 
J 0
(-2227 1039);
DISPLAY 0.638298 (-2227 1039);
PAINT MONO (-2227 1039);
FORCEPROP 2 LAST $XR2 96 
J 0
(-2407 1075);
DISPLAY 0.638298 (-2407 1075);
PAINT MONO (-2407 1075);
FORCEPROP 2 LAST $XR1 94 
J 0
(-2317 1075);
DISPLAY 0.638298 (-2317 1075);
PAINT MONO (-2317 1075);
FORCEPROP 2 LAST $XR0 129 
J 0
(-2227 1075);
DISPLAY 0.638298 (-2227 1075);
PAINT MONO (-2227 1075);
FORCEPROP 2 LAST CDS_LIB standard
J 0
(-1975 1075);
PAINT MONO (-1975 1075);
DISPLAY INVISIBLE (-1975 1075);
FORCEPROP 1 LAST OFFPAGE TRUE
J 0
(-1650 950);
DISPLAY 0.872340 (-1650 950);
DISPLAY INVISIBLE (-1650 950);
FORCEPROP 1 LAST COMMENT_BODY TRUE
J 0
(-1850 975);
DISPLAY 0.872340 (-1850 975);
PAINT GREEN (-1850 975);
DISPLAY INVISIBLE (-1850 975);
FORCEPROP 2 LAST PATH I9
J 0
(-1925 1150);
DISPLAY 1.021277 (-1925 1150);
DISPLAY INVISIBLE (-1925 1150);
FORCEADD TAP..1
(600 2275);
FORCEPROP 3 LASTPIN (550 2275) SIG_NAME M_G_CPU0_SA_DQ<10>
J 0
(560 2285);
DISPLAY 0.659574 (560 2285);
PAINT MONO (560 2285);
DISPLAY INVISIBLE (560 2285);
FORCEPROP 1 LASTPIN (550 2275) BN 10
J 0
(538 2283);
DISPLAY 0.680851 (538 2283);
PAINT GREEN (538 2283);
FORCEPROP 2 LAST CDS_LIB standard
J 0
(600 2275);
PAINT MONO (600 2275);
DISPLAY INVISIBLE (600 2275);
FORCEPROP 1 LAST BODY_TYPE PLUMBING
J 0
(600 2325);
DISPLAY 0.872340 (600 2325);
PAINT GREEN (600 2325);
DISPLAY INVISIBLE (600 2325);
FORCEPROP 1 LAST HDL_TAP TRUE
J 0
(925 2150);
DISPLAY 0.872340 (925 2150);
DISPLAY INVISIBLE (925 2150);
FORCEPROP 1 LAST PATH I90
J 0
(598 2275);
DISPLAY 0.872340 (598 2275);
PAINT GREEN (598 2275);
DISPLAY INVISIBLE (598 2275);
FORCEADD TAP..1
(600 2325);
FORCEPROP 3 LASTPIN (550 2325) SIG_NAME M_G_CPU0_SA_DQ<11>
J 0
(560 2335);
DISPLAY 0.659574 (560 2335);
PAINT MONO (560 2335);
DISPLAY INVISIBLE (560 2335);
FORCEPROP 1 LASTPIN (550 2325) BN 11
J 0
(538 2333);
DISPLAY 0.680851 (538 2333);
PAINT GREEN (538 2333);
FORCEPROP 2 LAST CDS_LIB standard
J 0
(600 2325);
PAINT MONO (600 2325);
DISPLAY INVISIBLE (600 2325);
FORCEPROP 1 LAST BODY_TYPE PLUMBING
J 0
(600 2375);
DISPLAY 0.872340 (600 2375);
PAINT GREEN (600 2375);
DISPLAY INVISIBLE (600 2375);
FORCEPROP 1 LAST HDL_TAP TRUE
J 0
(925 2200);
DISPLAY 0.872340 (925 2200);
DISPLAY INVISIBLE (925 2200);
FORCEPROP 1 LAST PATH I91
J 0
(598 2325);
DISPLAY 0.872340 (598 2325);
PAINT GREEN (598 2325);
DISPLAY INVISIBLE (598 2325);
FORCEADD TAP..1
(600 2375);
FORCEPROP 3 LASTPIN (550 2375) SIG_NAME M_G_CPU0_SA_DQ<12>
J 0
(560 2385);
DISPLAY 0.659574 (560 2385);
PAINT MONO (560 2385);
DISPLAY INVISIBLE (560 2385);
FORCEPROP 1 LASTPIN (550 2375) BN 12
J 0
(538 2383);
DISPLAY 0.680851 (538 2383);
PAINT GREEN (538 2383);
FORCEPROP 2 LAST CDS_LIB standard
J 0
(600 2375);
PAINT MONO (600 2375);
DISPLAY INVISIBLE (600 2375);
FORCEPROP 1 LAST BODY_TYPE PLUMBING
J 0
(600 2425);
DISPLAY 0.872340 (600 2425);
PAINT GREEN (600 2425);
DISPLAY INVISIBLE (600 2425);
FORCEPROP 1 LAST HDL_TAP TRUE
J 0
(925 2250);
DISPLAY 0.872340 (925 2250);
DISPLAY INVISIBLE (925 2250);
FORCEPROP 1 LAST PATH I92
J 0
(598 2375);
DISPLAY 0.872340 (598 2375);
PAINT GREEN (598 2375);
DISPLAY INVISIBLE (598 2375);
FORCEADD TAP..1
(600 2475);
FORCEPROP 3 LASTPIN (550 2475) SIG_NAME M_G_CPU0_SA_DQ<14>
J 0
(560 2485);
DISPLAY 0.659574 (560 2485);
PAINT MONO (560 2485);
DISPLAY INVISIBLE (560 2485);
FORCEPROP 1 LASTPIN (550 2475) BN 14
J 0
(538 2483);
DISPLAY 0.680851 (538 2483);
PAINT GREEN (538 2483);
FORCEPROP 2 LAST CDS_LIB standard
J 0
(600 2475);
PAINT MONO (600 2475);
DISPLAY INVISIBLE (600 2475);
FORCEPROP 1 LAST BODY_TYPE PLUMBING
J 0
(600 2525);
DISPLAY 0.872340 (600 2525);
PAINT GREEN (600 2525);
DISPLAY INVISIBLE (600 2525);
FORCEPROP 1 LAST HDL_TAP TRUE
J 0
(925 2350);
DISPLAY 0.872340 (925 2350);
DISPLAY INVISIBLE (925 2350);
FORCEPROP 1 LAST PATH I93
J 0
(598 2475);
DISPLAY 0.872340 (598 2475);
PAINT GREEN (598 2475);
DISPLAY INVISIBLE (598 2475);
FORCEADD TAP..1
(600 2425);
FORCEPROP 3 LASTPIN (550 2425) SIG_NAME M_G_CPU0_SA_DQ<13>
J 0
(560 2435);
DISPLAY 0.659574 (560 2435);
PAINT MONO (560 2435);
DISPLAY INVISIBLE (560 2435);
FORCEPROP 1 LASTPIN (550 2425) BN 13
J 0
(538 2433);
DISPLAY 0.680851 (538 2433);
PAINT GREEN (538 2433);
FORCEPROP 2 LAST CDS_LIB standard
J 0
(600 2425);
PAINT MONO (600 2425);
DISPLAY INVISIBLE (600 2425);
FORCEPROP 1 LAST BODY_TYPE PLUMBING
J 0
(600 2475);
DISPLAY 0.872340 (600 2475);
PAINT GREEN (600 2475);
DISPLAY INVISIBLE (600 2475);
FORCEPROP 1 LAST HDL_TAP TRUE
J 0
(925 2300);
DISPLAY 0.872340 (925 2300);
DISPLAY INVISIBLE (925 2300);
FORCEPROP 1 LAST PATH I94
J 0
(598 2425);
DISPLAY 0.872340 (598 2425);
PAINT GREEN (598 2425);
DISPLAY INVISIBLE (598 2425);
FORCEADD TAP..1
(600 2575);
FORCEPROP 3 LASTPIN (550 2575) SIG_NAME M_G_CPU0_SA_DQ<16>
J 0
(560 2585);
DISPLAY 0.659574 (560 2585);
PAINT MONO (560 2585);
DISPLAY INVISIBLE (560 2585);
FORCEPROP 1 LASTPIN (550 2575) BN 16
J 0
(538 2583);
DISPLAY 0.680851 (538 2583);
PAINT GREEN (538 2583);
FORCEPROP 2 LAST CDS_LIB standard
J 0
(600 2575);
PAINT MONO (600 2575);
DISPLAY INVISIBLE (600 2575);
FORCEPROP 1 LAST BODY_TYPE PLUMBING
J 0
(600 2625);
DISPLAY 0.872340 (600 2625);
PAINT GREEN (600 2625);
DISPLAY INVISIBLE (600 2625);
FORCEPROP 1 LAST HDL_TAP TRUE
J 0
(925 2450);
DISPLAY 0.872340 (925 2450);
DISPLAY INVISIBLE (925 2450);
FORCEPROP 1 LAST PATH I95
J 0
(598 2575);
DISPLAY 0.872340 (598 2575);
PAINT GREEN (598 2575);
DISPLAY INVISIBLE (598 2575);
FORCEADD TAP..1
(600 2525);
FORCEPROP 3 LASTPIN (550 2525) SIG_NAME M_G_CPU0_SA_DQ<15>
J 0
(560 2535);
DISPLAY 0.659574 (560 2535);
PAINT MONO (560 2535);
DISPLAY INVISIBLE (560 2535);
FORCEPROP 1 LASTPIN (550 2525) BN 15
J 0
(538 2533);
DISPLAY 0.680851 (538 2533);
PAINT GREEN (538 2533);
FORCEPROP 2 LAST CDS_LIB standard
J 0
(600 2525);
PAINT MONO (600 2525);
DISPLAY INVISIBLE (600 2525);
FORCEPROP 1 LAST BODY_TYPE PLUMBING
J 0
(600 2575);
DISPLAY 0.872340 (600 2575);
PAINT GREEN (600 2575);
DISPLAY INVISIBLE (600 2575);
FORCEPROP 1 LAST HDL_TAP TRUE
J 0
(925 2400);
DISPLAY 0.872340 (925 2400);
DISPLAY INVISIBLE (925 2400);
FORCEPROP 1 LAST PATH I96
J 0
(598 2525);
DISPLAY 0.872340 (598 2525);
PAINT GREEN (598 2525);
DISPLAY INVISIBLE (598 2525);
FORCEADD TAP..1
(600 2725);
FORCEPROP 3 LASTPIN (550 2725) SIG_NAME M_G_CPU0_SA_DQ<19>
J 0
(560 2735);
DISPLAY 0.659574 (560 2735);
PAINT MONO (560 2735);
DISPLAY INVISIBLE (560 2735);
FORCEPROP 1 LASTPIN (550 2725) BN 19
J 0
(538 2733);
DISPLAY 0.680851 (538 2733);
PAINT GREEN (538 2733);
FORCEPROP 2 LAST CDS_LIB standard
J 0
(600 2725);
PAINT MONO (600 2725);
DISPLAY INVISIBLE (600 2725);
FORCEPROP 1 LAST BODY_TYPE PLUMBING
J 0
(600 2775);
DISPLAY 0.872340 (600 2775);
PAINT GREEN (600 2775);
DISPLAY INVISIBLE (600 2775);
FORCEPROP 1 LAST HDL_TAP TRUE
J 0
(925 2600);
DISPLAY 0.872340 (925 2600);
DISPLAY INVISIBLE (925 2600);
FORCEPROP 1 LAST PATH I97
J 0
(598 2725);
DISPLAY 0.872340 (598 2725);
PAINT GREEN (598 2725);
DISPLAY INVISIBLE (598 2725);
FORCEADD TAP..1
(600 2675);
FORCEPROP 3 LASTPIN (550 2675) SIG_NAME M_G_CPU0_SA_DQ<18>
J 0
(560 2685);
DISPLAY 0.659574 (560 2685);
PAINT MONO (560 2685);
DISPLAY INVISIBLE (560 2685);
FORCEPROP 1 LASTPIN (550 2675) BN 18
J 0
(538 2683);
DISPLAY 0.680851 (538 2683);
PAINT GREEN (538 2683);
FORCEPROP 2 LAST CDS_LIB standard
J 0
(600 2675);
PAINT MONO (600 2675);
DISPLAY INVISIBLE (600 2675);
FORCEPROP 1 LAST BODY_TYPE PLUMBING
J 0
(600 2725);
DISPLAY 0.872340 (600 2725);
PAINT GREEN (600 2725);
DISPLAY INVISIBLE (600 2725);
FORCEPROP 1 LAST HDL_TAP TRUE
J 0
(925 2550);
DISPLAY 0.872340 (925 2550);
DISPLAY INVISIBLE (925 2550);
FORCEPROP 1 LAST PATH I98
J 0
(598 2675);
DISPLAY 0.872340 (598 2675);
PAINT GREEN (598 2675);
DISPLAY INVISIBLE (598 2675);
FORCEADD TAP..1
(600 2625);
FORCEPROP 3 LASTPIN (550 2625) SIG_NAME M_G_CPU0_SA_DQ<17>
J 0
(560 2635);
DISPLAY 0.659574 (560 2635);
PAINT MONO (560 2635);
DISPLAY INVISIBLE (560 2635);
FORCEPROP 1 LASTPIN (550 2625) BN 17
J 0
(538 2633);
DISPLAY 0.680851 (538 2633);
PAINT GREEN (538 2633);
FORCEPROP 2 LAST CDS_LIB standard
J 0
(600 2625);
PAINT MONO (600 2625);
DISPLAY INVISIBLE (600 2625);
FORCEPROP 1 LAST BODY_TYPE PLUMBING
J 0
(600 2675);
DISPLAY 0.872340 (600 2675);
PAINT GREEN (600 2675);
DISPLAY INVISIBLE (600 2675);
FORCEPROP 1 LAST HDL_TAP TRUE
J 0
(925 2500);
DISPLAY 0.872340 (925 2500);
DISPLAY INVISIBLE (925 2500);
FORCEPROP 1 LAST PATH I99
J 0
(598 2625);
DISPLAY 0.872340 (598 2625);
PAINT GREEN (598 2625);
DISPLAY INVISIBLE (598 2625);
FORCEADD CAD_NOTE..1
(2450 -1125);
FORCEPROP 0 LAST S1 PLACE THE BYPASS CAPS CLOSE TO DIMM
J 0
(2325 -1250);
DISPLAY 1.021277 (2325 -1250);
PAINT WHITE (2325 -1250);
FORCEPROP 2 LAST CDS_LIB logical_power
J 0
(2450 -1125);
PAINT MONO (2450 -1125);
DISPLAY INVISIBLE (2450 -1125);
FORCEPROP 1 LAST COMMENT_BODY TRUE
J 0
(2475 -1025);
DISPLAY 0.978723 (2475 -1025);
DISPLAY INVISIBLE (2475 -1025);
FORCEADD QUANTA_TITLE_BLOCK_C..1
(6925 -2425);
FORCEPROP 0 LAST CDS_CON_LAST_MODIFIED Fri Aug 25 14:01:14 2023
J 0
(5040 -2410);
PAINT MONO (5040 -2410);
DISPLAY INVISIBLE (5040 -2410);
FORCEPROP 1 LAST CUSTOM_TXT_CDS <CON_LAST_MODIFIED>
J 0
(5040 -2410);
DISPLAY 0.978723 (5040 -2410);
FORCEPROP 2 LAST CUSTOM_TXT_CDS <XR_PAGE_TITLE>
J 0
(-965 2825);
DISPLAY 0.638298 (-965 2825);
PAINT PINK (-965 2825);
DISPLAY INVISIBLE (-965 2825);
FORCEPROP 2 LAST CUSTOM_TXT_CDS <Q_NUMBER>
J 0
(5522 -2322);
DISPLAY 1.212766 (5522 -2322);
FORCEPROP 1 LAST CUSTOM_TXT_CDS <NAME_2>
J 0
(3750 -2375);
FORCEPROP 1 LAST CUSTOM_TXT_CDS <NAME_1>
J 0
(3750 -2250);
FORCEPROP 1 LAST CUSTOM_TXT_CDS <Q_PROJ>
J 0
(4543 -2323);
DISPLAY 1.212766 (4543 -2323);
FORCEPROP 1 LAST CUSTOM_TXT_CDS <Q_REV>
J 0
(6741 -2322);
DISPLAY 1.212766 (6741 -2322);
FORCEPROP 1 LAST CUSTOM_TXT_CDS <CON_PAGE_NUM> OF <CON_TOTAL_PAGES>
J 0
(6479 -2407);
DISPLAY 0.978723 (6479 -2407);
FORCEPROP 1 LAST Q_TITLE DDR5 - CPU0 CHG DIMM2(BLACK)
J 0
(-2441 -2399);
DISPLAY 2.446809 (-2441 -2399);
PAINT GREEN (-2441 -2399);
FORCEPROP 1 LAST Q_DEPT 
J 1
(3162 -2376);
DISPLAY 1.957447 (3162 -2376);
PAINT GREEN (3162 -2376);
FORCEPROP 1 LAST COMMENT_BODY TRUE
J 0
(6937 -2438);
DISPLAY 0.978723 (6937 -2438);
PAINT GREEN (6937 -2438);
DISPLAY INVISIBLE (6937 -2438);
FORCEPROP 2 LAST CDS_XR_PAGE_TITLE CR-95 : @S9S_MB_2U_LIB.S9S_MB_2U(SCH_1):PAGE95
J 0
(-965 2825);
DISPLAY 0.638298 (-965 2825);
PAINT PINK (-965 2825);
DISPLAY INVISIBLE (-965 2825);
FORCEPROP 2 LAST CDS_LIB pure_quanta
J 0
(6925 -2425);
PAINT MONO (6925 -2425);
DISPLAY INVISIBLE (6925 -2425);
FORCEPROP 1 LAST CDS_LMAN_SYM_OUTLINE -9475,6775,100,-125
J 0
(6925 -2425);
DISPLAY 0.468085 (6925 -2425);
PAINT GREEN (6925 -2425);
DISPLAY INVISIBLE (6925 -2425);
FORCEPROP 2 LAST PAGE_BORDER TRUE
J 0
(-965 2825);
DISPLAY 0.638298 (-965 2825);
PAINT PINK (-965 2825);
DISPLAY INVISIBLE (-965 2825);
WIRE 17 -1 (650 3300)(650 3350);
WIRE 17 -1 (650 3250)(650 3300);
WIRE 17 -1 (650 3350)(1375 3350);
FORCEPROP 2 LAST SIG_NAME M_G_CPU0_SA_DQ<31:0>
J 0
(715 3360);
DISPLAY 0.680851 (715 3360);
PAINT WHITE (715 3360);
WIRE 17 -1 (-1100 1900)(-1100 1950);
WIRE 17 -1 (-1100 1850)(-1100 1900);
WIRE 17 -1 (-1925 1950)(-1100 1950);
FORCEPROP 2 LAST SIG_NAME M_G_CPU0_SA_CB<7:0>
J 0
(-1835 1960);
DISPLAY 0.680851 (-1835 1960);
PAINT WHITE (-1835 1960);
WIRE 17 -1 (-1100 1800)(-1100 1850);
WIRE 17 -1 (-1100 1750)(-1100 1800);
WIRE 17 -1 (-1100 1700)(-1100 1750);
WIRE 17 -1 (-1100 1650)(-1100 1700);
WIRE 17 -1 (-1100 1600)(-1100 1650);
WIRE 17 -1 (-1100 1450)(-1100 1500);
WIRE 17 -1 (-1100 1400)(-1100 1450);
WIRE 17 -1 (-1925 1500)(-1100 1500);
FORCEPROP 2 LAST SIG_NAME M_G_CPU0_SB_CB<7:0>
J 0
(-1835 1510);
DISPLAY 0.680851 (-1835 1510);
PAINT WHITE (-1835 1510);
WIRE 17 -1 (-1100 3050)(-1100 3100);
WIRE 17 -1 (-1100 3100)(-1100 3150);
WIRE 17 -1 (-1100 3150)(-1100 3200);
WIRE 17 -1 (-1100 3200)(-1100 3250);
WIRE 17 -1 (-1100 3250)(-1100 3300);
WIRE 17 -1 (-1100 3300)(-1100 3350);
WIRE 17 -1 (-1925 3350)(-1100 3350);
FORCEPROP 2 LAST SIG_NAME M_G_CPU0_SA_CA<6:0>
J 0
(-1835 3360);
DISPLAY 0.680851 (-1835 3360);
PAINT WHITE (-1835 3360);
WIRE 17 -1 (-1100 2650)(-1100 2700);
WIRE 17 -1 (-1100 2700)(-1100 2750);
WIRE 17 -1 (-1100 2750)(-1100 2800);
WIRE 17 -1 (-1100 2800)(-1100 2850);
WIRE 17 -1 (-1100 2850)(-1100 2900);
WIRE 17 -1 (-1100 2900)(-1100 2950);
WIRE 17 -1 (-1925 2950)(-1100 2950);
FORCEPROP 2 LAST SIG_NAME M_G_CPU0_SB_CA<6:0>
J 0
(-1835 2960);
DISPLAY 0.680851 (-1835 2960);
PAINT WHITE (-1835 2960);
WIRE 17 -1 (-1100 1350)(-1100 1400);
WIRE 17 -1 (-1100 1300)(-1100 1350);
WIRE 17 -1 (-1100 1250)(-1100 1300);
WIRE 17 -1 (-1100 1200)(-1100 1250);
WIRE 17 -1 (-1100 1150)(-1100 1200);
WIRE 17 -1 (650 3200)(650 3250);
WIRE 17 -1 (650 3150)(650 3200);
WIRE 17 -1 (650 3100)(650 3150);
WIRE 17 -1 (650 3050)(650 3100);
WIRE 17 -1 (650 3000)(650 3050);
WIRE 17 -1 (650 2950)(650 3000);
WIRE 17 -1 (650 2900)(650 2950);
WIRE 17 -1 (650 2850)(650 2900);
WIRE 17 -1 (650 2800)(650 2850);
WIRE 17 -1 (650 2750)(650 2800);
WIRE 17 -1 (650 2700)(650 2750);
WIRE 17 -1 (650 2650)(650 2700);
WIRE 17 -1 (650 2600)(650 2650);
WIRE 17 -1 (650 2550)(650 2600);
WIRE 17 -1 (650 2500)(650 2550);
WIRE 17 -1 (650 2450)(650 2500);
WIRE 17 -1 (650 2400)(650 2450);
WIRE 17 -1 (650 2350)(650 2400);
WIRE 17 -1 (650 2300)(650 2350);
WIRE 17 -1 (650 2250)(650 2300);
WIRE 17 -1 (650 2200)(650 2250);
WIRE 17 -1 (650 2150)(650 2200);
WIRE 17 -1 (650 2100)(650 2150);
WIRE 17 -1 (650 2050)(650 2100);
WIRE 17 -1 (650 2000)(650 2050);
WIRE 17 -1 (650 1950)(650 2000);
WIRE 17 -1 (650 1900)(650 1950);
WIRE 17 -1 (650 1850)(650 1900);
WIRE 17 -1 (650 1800)(650 1850);
WIRE 17 -1 (650 1650)(650 1700);
WIRE 17 -1 (650 1600)(650 1650);
WIRE 17 -1 (650 1700)(1375 1700);
FORCEPROP 2 LAST SIG_NAME M_G_CPU0_SB_DQ<31:0>
J 0
(715 1710);
DISPLAY 0.680851 (715 1710);
PAINT WHITE (715 1710);
WIRE 17 -1 (650 1550)(650 1600);
WIRE 17 -1 (650 1500)(650 1550);
WIRE 17 -1 (650 1450)(650 1500);
WIRE 17 -1 (650 1400)(650 1450);
WIRE 17 -1 (650 1350)(650 1400);
WIRE 17 -1 (650 1300)(650 1350);
WIRE 17 -1 (650 1250)(650 1300);
WIRE 17 -1 (650 1200)(650 1250);
WIRE 17 -1 (650 1150)(650 1200);
WIRE 17 -1 (650 1100)(650 1150);
WIRE 17 -1 (650 1050)(650 1100);
WIRE 17 -1 (650 1000)(650 1050);
WIRE 17 -1 (650 950)(650 1000);
WIRE 17 -1 (650 900)(650 950);
WIRE 17 -1 (650 850)(650 900);
WIRE 17 -1 (650 800)(650 850);
WIRE 17 -1 (650 750)(650 800);
WIRE 17 -1 (650 700)(650 750);
WIRE 17 -1 (650 650)(650 700);
WIRE 17 -1 (650 600)(650 650);
WIRE 17 -1 (650 550)(650 600);
WIRE 17 -1 (650 500)(650 550);
WIRE 17 -1 (650 450)(650 500);
WIRE 17 -1 (650 400)(650 450);
WIRE 17 -1 (650 350)(650 400);
WIRE 17 -1 (650 300)(650 350);
WIRE 17 -1 (650 250)(650 300);
WIRE 17 -1 (650 200)(650 250);
WIRE 17 -1 (650 150)(650 200);
WIRE 17 -1 (3425 3250)(3425 3350);
WIRE 17 -1 (3425 3150)(3425 3250);
WIRE 17 -1 (3425 3350)(4450 3350);
FORCEPROP 2 LAST SIG_NAME M_G_CPU0_SA_DQS_DP<9:0>
J 0
(3665 3360);
DISPLAY 0.680851 (3665 3360);
PAINT WHITE (3665 3360);
WIRE 17 -1 (3425 3050)(3425 3150);
WIRE 17 -1 (3425 2950)(3425 3050);
WIRE 17 -1 (3425 2850)(3425 2950);
WIRE 17 -1 (3425 2850)(3425 2750);
WIRE 17 -1 (3425 2650)(3425 2750);
WIRE 17 -1 (3425 2550)(3425 2650);
WIRE 17 -1 (3425 2450)(3425 2550);
WIRE 17 -1 (3425 2200)(3425 2300);
WIRE 17 -1 (3425 2100)(3425 2200);
WIRE 17 -1 (3425 2300)(4450 2300);
FORCEPROP 2 LAST SIG_NAME M_G_CPU0_SB_DQS_DP<9:0>
J 0
(3665 2310);
DISPLAY 0.680851 (3665 2310);
PAINT WHITE (3665 2310);
WIRE 17 -1 (3425 2000)(3425 2100);
WIRE 17 -1 (3425 1900)(3425 2000);
WIRE 17 -1 (3425 1800)(3425 1900);
WIRE 17 -1 (3425 1800)(3425 1700);
WIRE 17 -1 (3425 1600)(3425 1700);
WIRE 17 -1 (3425 1500)(3425 1600);
WIRE 17 -1 (3425 1400)(3425 1500);
WIRE 17 -1 (3600 3200)(3600 3300);
WIRE 17 -1 (3600 3100)(3600 3200);
WIRE 17 -1 (3600 3300)(4450 3300);
FORCEPROP 2 LAST SIG_NAME M_G_CPU0_SA_DQS_DN<9:0>
J 0
(3665 3310);
DISPLAY 0.680851 (3665 3310);
PAINT WHITE (3665 3310);
WIRE 17 -1 (3600 3000)(3600 3100);
WIRE 17 -1 (3600 2900)(3600 3000);
WIRE 17 -1 (3600 2800)(3600 2900);
WIRE 17 -1 (3600 2800)(3600 2700);
WIRE 17 -1 (3600 2600)(3600 2700);
WIRE 17 -1 (3600 2500)(3600 2600);
WIRE 17 -1 (3600 2400)(3600 2500);
WIRE 17 -1 (3600 2150)(3600 2250);
WIRE 17 -1 (3600 2050)(3600 2150);
WIRE 17 -1 (3600 2250)(4450 2250);
FORCEPROP 2 LAST SIG_NAME M_G_CPU0_SB_DQS_DN<9:0>
J 0
(3665 2260);
DISPLAY 0.680851 (3665 2260);
PAINT WHITE (3665 2260);
WIRE 17 -1 (3600 1950)(3600 2050);
WIRE 17 -1 (3600 1850)(3600 1950);
WIRE 17 -1 (3600 1750)(3600 1850);
WIRE 17 -1 (3600 1750)(3600 1650);
WIRE 17 -1 (3600 1550)(3600 1650);
WIRE 17 -1 (3600 1450)(3600 1550);
WIRE 17 -1 (3600 1350)(3600 1450);
WIRE 16 -1 (-1875 1150)(-1875 875);
WIRE 16 -1 (5025 3825)(5025 3325);
WIRE 16 -1 (3325 -275)(3325 -325);
WIRE 16 -1 (2325 -450)(2325 -275);
WIRE 16 -1 (-825 -1000)(-825 -925);
WIRE 16 -1 (6725 -325)(6725 -25);
WIRE 16 -1 (5025 -325)(5025 75);
WIRE 16 -1 (3950 -875)(3950 -800);
WIRE 16 -1 (2325 -650)(2325 -875);
WIRE 16 3135 (4575 -50)(1975 -50);
WIRE 16 3135 (4575 -1350)(4575 -50);
WIRE 16 3135 (1975 -50)(1975 -1350);
WIRE 16 3135 (1975 -1350)(4575 -1350);
WIRE 16 -1 (-825 825)(-1850 825);
FORCEPROP 2 LAST SIG_NAME PD_CHG_CPU0_DIMM2_SAA
J 0
(-1860 835);
DISPLAY 0.680851 (-1860 835);
PAINT WHITE (-1860 835);
WIRE 16 -1 (-825 775)(-1850 775);
FORCEPROP 2 LAST SIG_NAME I3C_SPD_DDREFGH_CPU0_LVC1_SDA
J 0
(-1860 785);
DISPLAY 0.680851 (-1860 785);
PAINT WHITE (-1860 785);
WIRE 16 -1 (-1875 875)(-825 875);
WIRE 16 -1 (-825 975)(-1925 975);
FORCEPROP 2 LAST SIG_NAME M_G_CPU0_ALERT_N
J 0
(-1837 984);
DISPLAY 0.680851 (-1837 984);
PAINT WHITE (-1837 984);
WIRE 16 -1 (-1200 1075)(-1925 1075);
FORCEPROP 2 LAST SIG_NAME RST_M_GH_CPU0_FPGA_N
J 0
(-1837 1084);
DISPLAY 0.680851 (-1837 1084);
PAINT WHITE (-1837 1084);
WIRE 16 -1 (-1200 1075)(-1200 1025);
WIRE 16 -1 (-1200 1025)(-825 1025);
WIRE 16 -1 (-2325 625)(-2125 625);
WIRE 16 -1 (-2325 725)(-2325 625);
WIRE 16 -1 (-825 725)(-2325 725);
FORCEPROP 2 LAST SIG_NAME I3C_SPD_DDREFGH_CPU0_LVC1_SCL_R6
J 0
(-1885 735);
DISPLAY 0.680851 (-1885 735);
PAINT WHITE (-1885 735);
WIRE 16 -1 (-700 550)(-775 550);
WIRE 16 -1 (-1925 625)(-700 625);
FORCEPROP 2 LAST SIG_NAME I3C_SPD_DDREFGH_CPU0_LVC1_SCL
J 0
(-1785 635);
DISPLAY 0.680851 (-1785 635);
PAINT WHITE (-1785 635);
WIRE 16 -1 (-700 625)(-700 550);
WIRE 16 -1 (-825 475)(-1925 475);
FORCEPROP 2 LAST SIG_NAME PWRGD_CHG_CPU0_DIMM2
J 0
(-1837 484);
DISPLAY 0.680851 (-1837 484);
PAINT WHITE (-1837 484);
WIRE 16 -1 (-825 275)(-1925 275);
FORCEPROP 2 LAST SIG_NAME TP_CHG_CPU0_DIMM2_FRU_4
J 0
(-1837 284);
DISPLAY 0.680851 (-1837 284);
PAINT WHITE (-1837 284);
WIRE 16 -1 (-825 225)(-1925 225);
FORCEPROP 2 LAST SIG_NAME TP_CHG_CPU0_DIMM2_FRU_3
J 0
(-1837 234);
DISPLAY 0.680851 (-1837 234);
PAINT WHITE (-1837 234);
WIRE 16 -1 (-825 75)(-1925 75);
FORCEPROP 2 LAST SIG_NAME TP_CHG_CPU0_DIMM2_FRU_0
J 0
(-1837 84);
DISPLAY 0.680851 (-1837 84);
PAINT WHITE (-1837 84);
WIRE 16 -1 (-825 325)(-1925 325);
FORCEPROP 2 LAST SIG_NAME TP_CHG_CPU0_DIMM2_FRU_5
J 0
(-1837 334);
DISPLAY 0.680851 (-1837 334);
PAINT WHITE (-1837 334);
WIRE 16 -1 (-825 175)(-1925 175);
FORCEPROP 2 LAST SIG_NAME TP_CHG_CPU0_DIMM2_FRU_2
J 0
(-1837 184);
DISPLAY 0.680851 (-1837 184);
PAINT WHITE (-1837 184);
WIRE 16 -1 (-825 125)(-1925 125);
FORCEPROP 2 LAST SIG_NAME TP_CHG_CPU0_DIMM2_FRU_1
J 0
(-1837 134);
DISPLAY 0.680851 (-1837 134);
PAINT WHITE (-1837 134);
WIRE 16 -1 (3225 1575)(3325 1575);
WIRE 16 -1 (3225 1325)(3500 1325);
WIRE 16 -1 (3225 1525)(3500 1525);
WIRE 16 -1 (3225 1425)(3500 1425);
WIRE 16 -1 (3225 1625)(3500 1625);
WIRE 16 -1 (3225 1725)(3500 1725);
WIRE 16 -1 (3225 1825)(3500 1825);
WIRE 16 -1 (3225 1925)(3500 1925);
WIRE 16 -1 (3225 2025)(3500 2025);
WIRE 16 -1 (3225 2125)(3500 2125);
WIRE 16 -1 (3225 2225)(3500 2225);
WIRE 16 -1 (3225 2375)(3500 2375);
WIRE 16 -1 (3225 2475)(3500 2475);
WIRE 16 -1 (3225 2575)(3500 2575);
WIRE 16 -1 (3225 2675)(3500 2675);
WIRE 16 -1 (3225 2775)(3500 2775);
WIRE 16 -1 (3225 2875)(3500 2875);
WIRE 16 -1 (3225 2975)(3500 2975);
WIRE 16 -1 (3225 3075)(3500 3075);
WIRE 16 -1 (3225 3175)(3500 3175);
WIRE 16 -1 (3225 3275)(3500 3275);
WIRE 16 -1 (3225 1475)(3325 1475);
WIRE 16 -1 (3225 1375)(3325 1375);
WIRE 16 -1 (3225 1675)(3325 1675);
WIRE 16 -1 (3225 1775)(3325 1775);
WIRE 16 -1 (3225 1875)(3325 1875);
WIRE 16 -1 (3225 1975)(3325 1975);
WIRE 16 -1 (3225 2075)(3325 2075);
WIRE 16 -1 (3225 2175)(3325 2175);
WIRE 16 -1 (3225 2275)(3325 2275);
WIRE 16 -1 (3225 2525)(3325 2525);
WIRE 16 -1 (3225 2425)(3325 2425);
WIRE 16 -1 (3225 2625)(3325 2625);
WIRE 16 -1 (3225 2725)(3325 2725);
WIRE 16 -1 (3225 2825)(3325 2825);
WIRE 16 -1 (3225 2925)(3325 2925);
WIRE 16 -1 (3225 3025)(3325 3025);
WIRE 16 -1 (3225 3125)(3325 3125);
WIRE 16 -1 (3225 3225)(3325 3225);
WIRE 16 -1 (3225 3325)(3325 3325);
WIRE 16 -1 (-825 375)(-1925 375);
FORCEPROP 2 LAST SIG_NAME TP_CHG_CPU0_DIMM2_FRU_6
J 0
(-1837 384);
DISPLAY 0.680851 (-1837 384);
PAINT WHITE (-1837 384);
WIRE 16 -1 (5275 3225)(5025 3225);
WIRE 16 -1 (5025 3275)(5025 3225);
WIRE 16 -1 (5025 3275)(5275 3275);
WIRE 16 -1 (5025 3325)(5025 3275);
WIRE 16 -1 (5275 3325)(5025 3325);
WIRE 16 -1 (375 2575)(550 2575);
WIRE 16 -1 (375 2475)(550 2475);
WIRE 16 -1 (375 2825)(550 2825);
WIRE 16 -1 (375 1525)(550 1525);
WIRE 16 -1 (5025 75)(5275 75);
WIRE 16 -1 (5025 75)(5025 125);
WIRE 16 -1 (5025 125)(5275 125);
WIRE 16 -1 (5025 125)(5025 175);
WIRE 16 -1 (5025 175)(5275 175);
WIRE 16 -1 (5025 175)(5025 225);
WIRE 16 -1 (5025 225)(5275 225);
WIRE 16 -1 (5025 225)(5025 275);
WIRE 16 -1 (5025 275)(5275 275);
WIRE 16 -1 (5025 275)(5025 325);
WIRE 16 -1 (5025 325)(5275 325);
WIRE 16 -1 (5025 325)(5025 375);
WIRE 16 -1 (5025 375)(5275 375);
WIRE 16 -1 (5025 375)(5025 425);
WIRE 16 -1 (5025 425)(5275 425);
WIRE 16 -1 (5025 425)(5025 475);
WIRE 16 -1 (5025 475)(5275 475);
WIRE 16 -1 (5025 475)(5025 525);
WIRE 16 -1 (5025 525)(5275 525);
WIRE 16 -1 (5025 525)(5025 575);
WIRE 16 -1 (5275 575)(5025 575);
WIRE 16 -1 (5025 575)(5025 625);
WIRE 16 -1 (5025 625)(5275 625);
WIRE 16 -1 (5025 625)(5025 675);
WIRE 16 -1 (5025 675)(5275 675);
WIRE 16 -1 (5025 675)(5025 725);
WIRE 16 -1 (5025 725)(5275 725);
WIRE 16 -1 (5025 725)(5025 775);
WIRE 16 -1 (5025 775)(5275 775);
WIRE 16 -1 (5025 775)(5025 825);
WIRE 16 -1 (5025 825)(5275 825);
WIRE 16 -1 (5025 825)(5025 875);
WIRE 16 -1 (5025 875)(5275 875);
WIRE 16 -1 (5025 875)(5025 925);
WIRE 16 -1 (5025 925)(5275 925);
WIRE 16 -1 (5025 925)(5025 975);
WIRE 16 -1 (5025 975)(5275 975);
WIRE 16 -1 (5025 975)(5025 1025);
WIRE 16 -1 (5025 1025)(5275 1025);
WIRE 16 -1 (5025 1025)(5025 1075);
WIRE 16 -1 (5275 1075)(5025 1075);
WIRE 16 -1 (5025 1075)(5025 1125);
WIRE 16 -1 (5025 1125)(5275 1125);
WIRE 16 -1 (5025 1125)(5025 1175);
WIRE 16 -1 (5025 1175)(5275 1175);
WIRE 16 -1 (5025 1175)(5025 1225);
WIRE 16 -1 (5025 1225)(5275 1225);
WIRE 16 -1 (5025 1225)(5025 1275);
WIRE 16 -1 (5025 1275)(5275 1275);
WIRE 16 -1 (5025 1275)(5025 1325);
WIRE 16 -1 (5025 1325)(5275 1325);
WIRE 16 -1 (5025 1325)(5025 1375);
WIRE 16 -1 (5025 1375)(5275 1375);
WIRE 16 -1 (5025 1375)(5025 1425);
WIRE 16 -1 (5025 1425)(5275 1425);
WIRE 16 -1 (5025 1425)(5025 1475);
WIRE 16 -1 (5025 1475)(5275 1475);
WIRE 16 -1 (5025 1475)(5025 1525);
WIRE 16 -1 (5025 1525)(5275 1525);
WIRE 16 -1 (5025 1525)(5025 1575);
WIRE 16 -1 (5275 1575)(5025 1575);
WIRE 16 -1 (5025 1575)(5025 1625);
WIRE 16 -1 (5025 1625)(5275 1625);
WIRE 16 -1 (5025 1625)(5025 1675);
WIRE 16 -1 (5025 1675)(5275 1675);
WIRE 16 -1 (5025 1675)(5025 1725);
WIRE 16 -1 (5025 1725)(5275 1725);
WIRE 16 -1 (5025 1725)(5025 1775);
WIRE 16 -1 (5025 1775)(5275 1775);
WIRE 16 -1 (5025 1775)(5025 1825);
WIRE 16 -1 (5025 1825)(5275 1825);
WIRE 16 -1 (5025 1825)(5025 1875);
WIRE 16 -1 (5025 1875)(5275 1875);
WIRE 16 -1 (5025 1875)(5025 1925);
WIRE 16 -1 (5025 1925)(5275 1925);
WIRE 16 -1 (5025 1925)(5025 1975);
WIRE 16 -1 (5025 1975)(5275 1975);
WIRE 16 -1 (5025 1975)(5025 2025);
WIRE 16 -1 (5025 2025)(5275 2025);
WIRE 16 -1 (5025 2025)(5025 2075);
WIRE 16 -1 (5275 2075)(5025 2075);
WIRE 16 -1 (5025 2075)(5025 2125);
WIRE 16 -1 (5025 2125)(5275 2125);
WIRE 16 -1 (5025 2125)(5025 2175);
WIRE 16 -1 (5025 2175)(5275 2175);
WIRE 16 -1 (5025 2175)(5025 2225);
WIRE 16 -1 (5025 2225)(5275 2225);
WIRE 16 -1 (5025 2225)(5025 2275);
WIRE 16 -1 (5025 2275)(5275 2275);
WIRE 16 -1 (5025 2275)(5025 2325);
WIRE 16 -1 (5025 2325)(5275 2325);
WIRE 16 -1 (5025 2325)(5025 2375);
WIRE 16 -1 (5025 2375)(5275 2375);
WIRE 16 -1 (5025 2375)(5025 2425);
WIRE 16 -1 (5025 2425)(5275 2425);
WIRE 16 -1 (5025 2425)(5025 2475);
WIRE 16 -1 (5025 2475)(5275 2475);
WIRE 16 -1 (5025 2475)(5025 2525);
WIRE 16 -1 (5025 2525)(5275 2525);
WIRE 16 -1 (5025 2525)(5025 2575);
WIRE 16 -1 (5275 2575)(5025 2575);
WIRE 16 -1 (5025 2575)(5025 2625);
WIRE 16 -1 (5025 2625)(5275 2625);
WIRE 16 -1 (5025 2625)(5025 2675);
WIRE 16 -1 (5025 2675)(5275 2675);
WIRE 16 -1 (5025 2675)(5025 2725);
WIRE 16 -1 (5025 2725)(5275 2725);
WIRE 16 -1 (5025 2725)(5025 2775);
WIRE 16 -1 (5025 2775)(5275 2775);
WIRE 16 -1 (5025 2775)(5025 2825);
WIRE 16 -1 (5025 2825)(5275 2825);
WIRE 16 -1 (5025 2825)(5025 2875);
WIRE 16 -1 (5025 2875)(5275 2875);
WIRE 16 -1 (5025 2875)(5025 2925);
WIRE 16 -1 (5025 2925)(5275 2925);
WIRE 16 -1 (5025 2925)(5025 2975);
WIRE 16 -1 (5025 2975)(5275 2975);
WIRE 16 -1 (5025 2975)(5025 3025);
WIRE 16 -1 (5025 3025)(5275 3025);
WIRE 16 -1 (5025 3025)(5025 3075);
WIRE 16 -1 (5275 3075)(5025 3075);
WIRE 16 -1 (5025 3075)(5025 3125);
WIRE 16 -1 (5025 3125)(5275 3125);
WIRE 16 -1 (5025 3125)(5025 3175);
WIRE 16 -1 (5275 3175)(5025 3175);
WIRE 16 -1 (6475 -25)(6725 -25);
WIRE 16 -1 (6725 -25)(6725 25);
WIRE 16 -1 (6475 25)(6725 25);
WIRE 16 -1 (6475 75)(6725 75);
WIRE 16 -1 (6725 25)(6725 75);
WIRE 16 -1 (6475 175)(6725 175);
WIRE 16 -1 (6725 75)(6725 175);
WIRE 16 -1 (6475 225)(6725 225);
WIRE 16 -1 (6725 225)(6725 175);
WIRE 16 -1 (6475 275)(6725 275);
WIRE 16 -1 (6725 225)(6725 275);
WIRE 16 -1 (6475 325)(6725 325);
WIRE 16 -1 (6725 325)(6725 275);
WIRE 16 -1 (6475 375)(6725 375);
WIRE 16 -1 (6725 375)(6725 325);
WIRE 16 -1 (6475 425)(6725 425);
WIRE 16 -1 (6725 425)(6725 375);
WIRE 16 -1 (6475 475)(6725 475);
WIRE 16 -1 (6725 475)(6725 425);
WIRE 16 -1 (6475 525)(6725 525);
WIRE 16 -1 (6725 525)(6725 475);
WIRE 16 -1 (6475 575)(6725 575);
WIRE 16 -1 (6725 575)(6725 525);
WIRE 16 -1 (6725 625)(6475 625);
WIRE 16 -1 (6725 625)(6725 575);
WIRE 16 -1 (6725 675)(6475 675);
WIRE 16 -1 (6725 675)(6725 625);
WIRE 16 -1 (6725 725)(6475 725);
WIRE 16 -1 (6725 725)(6725 675);
WIRE 16 -1 (6475 775)(6725 775);
WIRE 16 -1 (6725 725)(6725 775);
WIRE 16 -1 (6725 825)(6475 825);
WIRE 16 -1 (6725 775)(6725 825);
WIRE 16 -1 (6725 875)(6475 875);
WIRE 16 -1 (6725 875)(6725 825);
WIRE 16 -1 (6725 925)(6475 925);
WIRE 16 -1 (6725 925)(6725 875);
WIRE 16 -1 (6725 975)(6475 975);
WIRE 16 -1 (6725 975)(6725 925);
WIRE 16 -1 (6725 1025)(6725 975);
WIRE 16 -1 (6475 1025)(6725 1025);
WIRE 16 -1 (6475 1075)(6725 1075);
WIRE 16 -1 (6725 1075)(6725 1025);
WIRE 16 -1 (6475 1125)(6725 1125);
WIRE 16 -1 (6725 1075)(6725 1125);
WIRE 16 -1 (6475 1175)(6725 1175);
WIRE 16 -1 (6725 1175)(6725 1125);
WIRE 16 -1 (6475 1225)(6725 1225);
WIRE 16 -1 (6725 1225)(6725 1175);
WIRE 16 -1 (6475 1275)(6725 1275);
WIRE 16 -1 (6725 1275)(6725 1225);
WIRE 16 -1 (6475 1325)(6725 1325);
WIRE 16 -1 (6725 1325)(6725 1275);
WIRE 16 -1 (6475 1375)(6725 1375);
WIRE 16 -1 (6725 1375)(6725 1325);
WIRE 16 -1 (6725 1425)(6475 1425);
WIRE 16 -1 (6725 1425)(6725 1375);
WIRE 16 -1 (6725 1475)(6475 1475);
WIRE 16 -1 (6725 1475)(6725 1425);
WIRE 16 -1 (6475 1525)(6725 1525);
WIRE 16 -1 (6725 1525)(6725 1475);
WIRE 16 -1 (6475 1575)(6725 1575);
WIRE 16 -1 (6725 1575)(6725 1525);
WIRE 16 -1 (6475 1625)(6725 1625);
WIRE 16 -1 (6725 1575)(6725 1625);
WIRE 16 -1 (6475 1675)(6725 1675);
WIRE 16 -1 (6725 1675)(6725 1625);
WIRE 16 -1 (6475 1725)(6725 1725);
WIRE 16 -1 (6725 1725)(6725 1675);
WIRE 16 -1 (6475 1775)(6725 1775);
WIRE 16 -1 (6725 1775)(6725 1725);
WIRE 16 -1 (6475 1825)(6725 1825);
WIRE 16 -1 (6725 1825)(6725 1775);
WIRE 16 -1 (6475 1875)(6725 1875);
WIRE 16 -1 (6725 1875)(6725 1825);
WIRE 16 -1 (6725 1925)(6475 1925);
WIRE 16 -1 (6725 1925)(6725 1875);
WIRE 16 -1 (6725 1975)(6475 1975);
WIRE 16 -1 (6725 1975)(6725 1925);
WIRE 16 -1 (6475 2025)(6725 2025);
WIRE 16 -1 (6725 2025)(6725 1975);
WIRE 16 -1 (6725 2075)(6725 2025);
WIRE 16 -1 (6475 2075)(6725 2075);
WIRE 16 -1 (6475 2125)(6725 2125);
WIRE 16 -1 (6725 2075)(6725 2125);
WIRE 16 -1 (6475 2175)(6725 2175);
WIRE 16 -1 (6725 2175)(6725 2125);
WIRE 16 -1 (6475 2225)(6725 2225);
WIRE 16 -1 (6725 2225)(6725 2175);
WIRE 16 -1 (6475 2275)(6725 2275);
WIRE 16 -1 (6725 2275)(6725 2225);
WIRE 16 -1 (6475 2325)(6725 2325);
WIRE 16 -1 (6725 2325)(6725 2275);
WIRE 16 -1 (6475 2375)(6725 2375);
WIRE 16 -1 (6725 2375)(6725 2325);
WIRE 16 -1 (6725 2425)(6475 2425);
WIRE 16 -1 (6725 2425)(6725 2375);
WIRE 16 -1 (6725 2475)(6475 2475);
WIRE 16 -1 (6725 2475)(6725 2425);
WIRE 16 -1 (6475 2525)(6725 2525);
WIRE 16 -1 (6725 2525)(6725 2475);
WIRE 16 -1 (6475 2575)(6725 2575);
WIRE 16 -1 (6725 2575)(6725 2525);
WIRE 16 -1 (6475 2625)(6725 2625);
WIRE 16 -1 (6725 2575)(6725 2625);
WIRE 16 -1 (6475 2675)(6725 2675);
WIRE 16 -1 (6725 2675)(6725 2625);
WIRE 16 -1 (6475 2725)(6725 2725);
WIRE 16 -1 (6725 2725)(6725 2675);
WIRE 16 -1 (6475 2775)(6725 2775);
WIRE 16 -1 (6725 2775)(6725 2725);
WIRE 16 -1 (6475 2825)(6725 2825);
WIRE 16 -1 (6725 2825)(6725 2775);
WIRE 16 -1 (6475 2875)(6725 2875);
WIRE 16 -1 (6725 2875)(6725 2825);
WIRE 16 -1 (6475 2925)(6725 2925);
WIRE 16 -1 (6725 2925)(6725 2875);
WIRE 16 -1 (6475 2975)(6725 2975);
WIRE 16 -1 (6725 2975)(6725 2925);
WIRE 16 -1 (6475 3025)(6725 3025);
WIRE 16 -1 (6725 3025)(6725 2975);
WIRE 16 -1 (6725 3075)(6725 3025);
WIRE 16 -1 (6475 3075)(6725 3075);
WIRE 16 -1 (6475 3125)(6725 3125);
WIRE 16 -1 (6725 3125)(6725 3075);
WIRE 16 -1 (6475 3175)(6725 3175);
WIRE 16 -1 (6725 3175)(6725 3125);
WIRE 16 -1 (6475 3225)(6725 3225);
WIRE 16 -1 (6725 3225)(6725 3175);
WIRE 16 -1 (6475 3275)(6725 3275);
WIRE 16 -1 (6725 3275)(6725 3225);
WIRE 16 -1 (6725 3325)(6725 3275);
WIRE 16 -1 (6475 3325)(6725 3325);
WIRE 16 -1 (375 875)(550 875);
WIRE 16 -1 (-825 2475)(-1925 2475);
FORCEPROP 2 LAST SIG_NAME M_G_CPU0_SB_PAR
J 0
(-1837 2484);
DISPLAY 0.680851 (-1837 2484);
PAINT WHITE (-1837 2484);
WIRE 16 -1 (-825 2525)(-1925 2525);
FORCEPROP 2 LAST SIG_NAME M_G_CPU0_SA_PAR
J 0
(-1837 2534);
DISPLAY 0.680851 (-1837 2534);
PAINT WHITE (-1837 2534);
WIRE 16 -1 (-825 -125)(-1925 -125);
FORCEPROP 2 LAST SIG_NAME M_G_CPU0_SB_RSP<1>
J 0
(-1837 -116);
DISPLAY 0.680851 (-1837 -116);
PAINT WHITE (-1837 -116);
WIRE 16 -1 (-825 -75)(-1925 -75);
FORCEPROP 2 LAST SIG_NAME M_G_CPU0_SA_RSP<1>
J 0
(-1837 -66);
DISPLAY 0.680851 (-1837 -66);
PAINT WHITE (-1837 -66);
WIRE 16 -1 (375 125)(550 125);
WIRE 16 -1 (375 175)(550 175);
WIRE 16 -1 (375 225)(550 225);
WIRE 16 -1 (375 275)(550 275);
WIRE 16 -1 (375 325)(550 325);
WIRE 16 -1 (375 375)(550 375);
WIRE 16 -1 (375 425)(550 425);
WIRE 16 -1 (375 475)(550 475);
WIRE 16 -1 (375 525)(550 525);
WIRE 16 -1 (375 575)(550 575);
WIRE 16 -1 (375 625)(550 625);
WIRE 16 -1 (375 675)(550 675);
WIRE 16 -1 (375 725)(550 725);
WIRE 16 -1 (375 775)(550 775);
WIRE 16 -1 (375 825)(550 825);
WIRE 16 -1 (375 925)(550 925);
WIRE 16 -1 (375 975)(550 975);
WIRE 16 -1 (375 1025)(550 1025);
WIRE 16 -1 (375 1075)(550 1075);
WIRE 16 -1 (375 1125)(550 1125);
WIRE 16 -1 (375 1175)(550 1175);
WIRE 16 -1 (375 1225)(550 1225);
WIRE 16 -1 (375 1275)(550 1275);
WIRE 16 -1 (375 1325)(550 1325);
WIRE 16 -1 (375 1375)(550 1375);
WIRE 16 -1 (375 1425)(550 1425);
WIRE 16 -1 (375 1475)(550 1475);
WIRE 16 -1 (375 1575)(550 1575);
WIRE 16 -1 (375 1625)(550 1625);
WIRE 16 -1 (375 1675)(550 1675);
WIRE 16 -1 (375 1775)(550 1775);
WIRE 16 -1 (375 1825)(550 1825);
WIRE 16 -1 (375 1875)(550 1875);
WIRE 16 -1 (375 1925)(550 1925);
WIRE 16 -1 (375 1975)(550 1975);
WIRE 16 -1 (375 2025)(550 2025);
WIRE 16 -1 (375 2075)(550 2075);
WIRE 16 -1 (375 2125)(550 2125);
WIRE 16 -1 (375 2175)(550 2175);
WIRE 16 -1 (375 2225)(550 2225);
WIRE 16 -1 (375 2275)(550 2275);
WIRE 16 -1 (375 2325)(550 2325);
WIRE 16 -1 (375 2375)(550 2375);
WIRE 16 -1 (375 2425)(550 2425);
WIRE 16 -1 (375 2525)(550 2525);
WIRE 16 -1 (375 2625)(550 2625);
WIRE 16 -1 (375 2675)(550 2675);
WIRE 16 -1 (375 2725)(550 2725);
WIRE 16 -1 (375 2775)(550 2775);
WIRE 16 -1 (375 2875)(550 2875);
WIRE 16 -1 (375 2925)(550 2925);
WIRE 16 -1 (375 2975)(550 2975);
WIRE 16 -1 (375 3025)(550 3025);
WIRE 16 -1 (375 3075)(550 3075);
WIRE 16 -1 (375 3125)(550 3125);
WIRE 16 -1 (375 3175)(550 3175);
WIRE 16 -1 (375 3225)(550 3225);
WIRE 16 -1 (375 3275)(550 3275);
WIRE 16 -1 (-825 2225)(-1925 2225);
FORCEPROP 2 LAST SIG_NAME M_G_CPU0_SB_CS_N<3>
J 0
(-1837 2234);
DISPLAY 0.680851 (-1837 2234);
PAINT WHITE (-1837 2234);
WIRE 16 -1 (-825 2375)(-1925 2375);
FORCEPROP 2 LAST SIG_NAME M_G_CPU0_SA_CS_N<3>
J 0
(-1837 2384);
DISPLAY 0.680851 (-1837 2384);
PAINT WHITE (-1837 2384);
WIRE 16 -1 (-825 2175)(-1925 2175);
FORCEPROP 2 LAST SIG_NAME M_G_CPU0_SB_CS_N<2>
J 0
(-1837 2184);
DISPLAY 0.680851 (-1837 2184);
PAINT WHITE (-1837 2184);
WIRE 16 -1 (-825 2325)(-1925 2325);
FORCEPROP 2 LAST SIG_NAME M_G_CPU0_SA_CS_N<2>
J 0
(-1837 2334);
DISPLAY 0.680851 (-1837 2334);
PAINT WHITE (-1837 2334);
WIRE 16 -1 (-825 2075)(-1925 2075);
FORCEPROP 2 LAST SIG_NAME M_G_CPU0_CLK_DP<1>
J 0
(-1837 2084);
DISPLAY 0.680851 (-1837 2084);
PAINT WHITE (-1837 2084);
WIRE 16 -1 (-825 2025)(-1925 2025);
FORCEPROP 2 LAST SIG_NAME M_G_CPU0_CLK_DN<1>
J 0
(-1837 2034);
DISPLAY 0.680851 (-1837 2034);
PAINT WHITE (-1837 2034);
WIRE 16 -1 (-1000 1125)(-825 1125);
WIRE 16 -1 (-1000 1175)(-825 1175);
WIRE 16 -1 (-1000 1225)(-825 1225);
WIRE 16 -1 (-1000 1275)(-825 1275);
WIRE 16 -1 (-1000 1325)(-825 1325);
WIRE 16 -1 (-1000 1375)(-825 1375);
WIRE 16 -1 (-1000 1425)(-825 1425);
WIRE 16 -1 (-1000 1575)(-825 1575);
WIRE 16 -1 (-1000 1675)(-825 1675);
WIRE 16 -1 (-1000 1725)(-825 1725);
WIRE 16 -1 (-1000 1825)(-825 1825);
WIRE 16 -1 (-1000 1875)(-825 1875);
WIRE 16 -1 (-1000 2925)(-825 2925);
WIRE 16 -1 (-1000 3325)(-825 3325);
WIRE 16 -1 (-1000 2875)(-825 2875);
WIRE 16 -1 (-1000 3275)(-825 3275);
WIRE 16 -1 (-1000 2825)(-825 2825);
WIRE 16 -1 (-1000 3225)(-825 3225);
WIRE 16 -1 (-1000 2775)(-825 2775);
WIRE 16 -1 (-1000 3175)(-825 3175);
WIRE 16 -1 (-1000 2725)(-825 2725);
WIRE 16 -1 (-1000 3125)(-825 3125);
WIRE 16 -1 (-1000 2675)(-825 2675);
WIRE 16 -1 (-1000 3075)(-825 3075);
WIRE 16 -1 (-1000 2625)(-825 2625);
WIRE 16 -1 (-1000 3025)(-825 3025);
WIRE 16 -1 (-1000 1475)(-825 1475);
WIRE 16 -1 (-1000 1625)(-825 1625);
WIRE 16 -1 (-1000 1775)(-825 1775);
WIRE 16 -1 (-1000 1925)(-825 1925);
WIRE 16 -1 (375 3325)(550 3325);
WIRE 16 -1 (-825 -625)(-1925 -625);
FORCEPROP 2 LAST SIG_NAME PD_CHG_CPU0_DIMM2_SAA
J 0
(-1837 -616);
DISPLAY 0.680851 (-1837 -616);
PAINT WHITE (-1837 -616);
WIRE 16 -1 (-825 -725)(-825 -625);
WIRE 16 -1 (3325 -325)(3325 -450);
WIRE 16 -1 (3950 -325)(3325 -325);
WIRE 16 -1 (3950 -450)(3950 -325);
WIRE 16 -1 (3325 -800)(3325 -650);
WIRE 16 -1 (3950 -800)(3325 -800);
WIRE 16 -1 (3950 -800)(3950 -650);
DOT 1 (6725 25);
DOT 1 (6725 75);
DOT 1 (6725 -25);
DOT 1 (5025 125);
DOT 1 (6725 3225);
DOT 1 (6725 3275);
DOT 1 (6725 3175);
DOT 1 (6725 3125);
DOT 1 (6725 3075);
DOT 1 (6725 3025);
DOT 1 (6725 2975);
DOT 1 (6725 2875);
DOT 1 (6725 2925);
DOT 1 (6725 2825);
DOT 1 (6725 2775);
DOT 1 (6725 2725);
DOT 1 (6725 2575);
DOT 1 (6725 2625);
DOT 1 (6725 2675);
DOT 1 (6725 2525);
DOT 1 (6725 2475);
DOT 1 (6725 2325);
DOT 1 (6725 2375);
DOT 1 (6725 2275);
DOT 1 (6725 2225);
DOT 1 (6725 2075);
DOT 1 (6725 2125);
DOT 1 (6725 2175);
DOT 1 (6725 1975);
DOT 1 (6725 2025);
DOT 1 (6725 1925);
DOT 1 (6725 1875);
DOT 1 (6725 1825);
DOT 1 (6725 1725);
DOT 1 (6725 1775);
DOT 1 (6725 1675);
DOT 1 (6725 1625);
DOT 1 (6725 1575);
DOT 1 (6725 1425);
DOT 1 (6725 1525);
DOT 1 (6725 1475);
DOT 1 (6725 1375);
DOT 1 (6725 1325);
DOT 1 (6725 1175);
DOT 1 (6725 1225);
DOT 1 (6725 1275);
DOT 1 (6725 1075);
DOT 1 (6725 1125);
DOT 1 (6725 1025);
DOT 1 (6725 975);
DOT 1 (6725 925);
DOT 1 (6725 825);
DOT 1 (6725 875);
DOT 1 (6725 775);
DOT 1 (6725 725);
DOT 1 (6725 675);
DOT 1 (6725 575);
DOT 1 (6725 625);
DOT 1 (6725 525);
DOT 1 (6725 475);
DOT 1 (6725 425);
DOT 1 (6725 275);
DOT 1 (6725 375);
DOT 1 (6725 325);
DOT 1 (6725 225);
DOT 1 (6725 175);
DOT 1 (5025 3275);
DOT 1 (5025 3325);
DOT 1 (5025 3125);
DOT 1 (5025 3075);
DOT 1 (5025 3025);
DOT 1 (5025 2975);
DOT 1 (5025 2925);
DOT 1 (5025 2875);
DOT 1 (5025 2825);
DOT 1 (5025 2775);
DOT 1 (5025 2725);
DOT 1 (5025 2675);
DOT 1 (5025 2625);
DOT 1 (5025 2575);
DOT 1 (5025 2525);
DOT 1 (5025 2475);
DOT 1 (5025 2425);
DOT 1 (5025 2375);
DOT 1 (5025 2325);
DOT 1 (5025 2275);
DOT 1 (5025 2225);
DOT 1 (5025 2175);
DOT 1 (5025 2125);
DOT 1 (5025 2075);
DOT 1 (5025 2025);
DOT 1 (5025 1975);
DOT 1 (5025 1925);
DOT 1 (5025 1875);
DOT 1 (5025 1825);
DOT 1 (5025 1775);
DOT 1 (5025 1725);
DOT 1 (5025 1675);
DOT 1 (5025 1625);
DOT 1 (5025 1575);
DOT 1 (5025 1525);
DOT 1 (5025 1475);
DOT 1 (5025 1425);
DOT 1 (5025 1375);
DOT 1 (5025 1325);
DOT 1 (5025 1275);
DOT 1 (5025 1225);
DOT 1 (5025 1125);
DOT 1 (5025 1075);
DOT 1 (5025 975);
DOT 1 (5025 925);
DOT 1 (5025 875);
DOT 1 (5025 825);
DOT 1 (5025 775);
DOT 1 (5025 725);
DOT 1 (5025 675);
DOT 1 (5025 625);
DOT 1 (5025 575);
DOT 1 (5025 525);
DOT 1 (5025 475);
DOT 1 (5025 425);
DOT 1 (5025 375);
DOT 1 (5025 325);
DOT 1 (5025 275);
DOT 1 (5025 225);
DOT 1 (5025 175);
DOT 1 (5025 75);
DOT 1 (3950 -800);
DOT 1 (3325 -325);
DOT 1 (6725 2425);
DOT 1 (5025 1175);
DOT 1 (5025 1025);
FORCENOTE
20210728 MODIFY FOR GT
(-2325 4025) 0;
DISPLAY LEFT (-2325 4025);
DISPLAY 2.510638 (-2325 4025);
PAINT PINK (-2325 4025);
QUIT
